FILE_TYPE = MACRO_DRAWING;
SET COLOR_WIRE YELLOW;
SET COLOR_PROP MONO;
SET COLOR_DOT WHITE;
SET COLOR_ARC YELLOW;
SET COLOR_BODY GREEN;
SET COLOR_NOTE MONO;
SET PROP_DISPLAY VALUE;
SET PAGE_NUMBER P242;
FORCEADD GND..1
(-7400 1100);
FORCEPROP 3 LASTPIN (-7400 1150) SIG_NAME GND\g
J 0
(-7390 1160);
DISPLAY 0.659574 (-7390 1160);
PAINT MONO (-7390 1160);
DISPLAY INVISIBLE (-7390 1160);
FORCEPROP 1 LAST HDL_POWER GND
J 0
(-7400 1250);
DISPLAY 1.723404 (-7400 1250);
PAINT GREEN (-7400 1250);
DISPLAY INVISIBLE (-7400 1250);
FORCEPROP 1 LAST BODY_TYPE PLUMBING
J 0
(-7445 1057);
DISPLAY 0.340426 (-7445 1057);
PAINT GREEN (-7445 1057);
DISPLAY INVISIBLE (-7445 1057);
FORCEPROP 1 LAST PATH I1
J 0
(-7325 1100);
DISPLAY 0.872340 (-7325 1100);
PAINT AQUA (-7325 1100);
DISPLAY INVISIBLE (-7325 1100);
FORCEPROP 1 LAST VOLTAGE 0
J 0
(-7400 1100);
PAINT SKYBLUE (-7400 1100);
DISPLAY INVISIBLE (-7400 1100);
FORCEPROP 2 LAST ROOM VDDQ_ABC_PWR_VR
J 0
(-7950 1175);
DISPLAY 1.936170 (-7950 1175);
PAINT ORANGE (-7950 1175);
DISPLAY INVISIBLE (-7950 1175);
FORCEPROP 2 LAST BOM_COST PROC_VRD_VCCIN_CPU0
J 0
(-7775 1175);
DISPLAY 1.446809 (-7775 1175);
PAINT MONO (-7775 1175);
DISPLAY INVISIBLE (-7775 1175);
FORCEPROP 1 LAST SIZE 1B
J 0
(-7325 1050);
DISPLAY 1.723404 (-7325 1050);
PAINT GREEN (-7325 1050);
DISPLAY INVISIBLE (-7325 1050);
FORCEPROP 2 LAST CDS_LIB mstr_symbols
J 0
(-7400 1100);
PAINT MONO (-7400 1100);
DISPLAY INVISIBLE (-7400 1100);
FORCEADD GND..1
(-7400 3375);
FORCEPROP 3 LASTPIN (-7400 3425) SIG_NAME GND\g
J 0
(-7390 3435);
DISPLAY 0.659574 (-7390 3435);
PAINT MONO (-7390 3435);
DISPLAY INVISIBLE (-7390 3435);
FORCEPROP 1 LAST HDL_POWER GND
J 0
(-7400 3525);
DISPLAY 1.723404 (-7400 3525);
PAINT GREEN (-7400 3525);
DISPLAY INVISIBLE (-7400 3525);
FORCEPROP 1 LAST BODY_TYPE PLUMBING
J 0
(-7445 3332);
DISPLAY 0.340426 (-7445 3332);
PAINT GREEN (-7445 3332);
DISPLAY INVISIBLE (-7445 3332);
FORCEPROP 1 LAST PATH I10
J 0
(-7325 3375);
DISPLAY 0.872340 (-7325 3375);
PAINT AQUA (-7325 3375);
DISPLAY INVISIBLE (-7325 3375);
FORCEPROP 2 LAST CDS_LIB mstr_symbols
J 0
(-7400 3375);
PAINT MONO (-7400 3375);
DISPLAY INVISIBLE (-7400 3375);
FORCEPROP 1 LAST VOLTAGE 0
J 0
(-7400 3375);
PAINT SKYBLUE (-7400 3375);
DISPLAY INVISIBLE (-7400 3375);
FORCEPROP 2 LAST ROOM VDDQ_ABC_PWR_VR
J 0
(-7950 3450);
DISPLAY 1.936170 (-7950 3450);
PAINT ORANGE (-7950 3450);
DISPLAY INVISIBLE (-7950 3450);
FORCEPROP 2 LAST BOM_COST PROC_VRD_VCCIN_CPU0
J 0
(-7775 3450);
DISPLAY 1.446809 (-7775 3450);
PAINT MONO (-7775 3450);
DISPLAY INVISIBLE (-7775 3450);
FORCEPROP 1 LAST SIZE 1B
J 0
(-7325 3325);
DISPLAY 1.723404 (-7325 3325);
PAINT GREEN (-7325 3325);
DISPLAY INVISIBLE (-7325 3325);
FORCEADD CAP..1
(-7400 3900);
FORCEPROP 1 LAST MATERIAL X5R
J 0
(-7350 3800);
DISPLAY 0.617021 (-7350 3800);
PAINT SKYBLUE (-7350 3800);
FORCEPROP 1 LAST VALUE 100UF
J 0
(-7350 3950);
DISPLAY 0.617021 (-7350 3950);
PAINT SKYBLUE (-7350 3950);
FORCEPROP 1 LAST PACK_TYPE 0805
J 0
(-7350 3700);
DISPLAY 0.617021 (-7350 3700);
PAINT SKYBLUE (-7350 3700);
FORCEPROP 1 LAST PART_NUMBER 602433-112
J 0
(-7350 3750);
DISPLAY 0.617021 (-7350 3750);
PAINT BLUE (-7350 3750);
FORCEPROP 1 LAST TOLERANCE 20%
J 0
(-7350 3850);
DISPLAY 0.617021 (-7350 3850);
PAINT SKYBLUE (-7350 3850);
FORCEPROP 1 LAST VOLTAGE 4V
J 0
(-7350 3900);
DISPLAY 0.617021 (-7350 3900);
PAINT SKYBLUE (-7350 3900);
FORCEPROP 1 LAST LOCATION C5G21
J 0
(-7350 4000);
DISPLAY 0.617021 (-7350 4000);
PAINT AQUA (-7350 4000);
FORCEPROP 0 LAST SIDE_SKU 1S
J 0
(-7500 3975);
DISPLAY 1.021277 (-7500 3975);
PAINT ORANGE (-7500 3975);
FORCEPROP 1 LAST PATH I11
J 0
(-7350 4050);
DISPLAY 0.978723 (-7350 4050);
PAINT WHITE (-7350 4050);
DISPLAY INVISIBLE (-7350 4050);
FORCEPROP 0 LAST CDS_SEC 1
J 0
(-7350 4050);
PAINT MONO (-7350 4050);
DISPLAY INVISIBLE (-7350 4050);
FORCEPROP 0 LAST $SEC 1
J 0
(-7350 4050);
PAINT MONO (-7350 4050);
DISPLAY INVISIBLE (-7350 4050);
FORCEPROP 0 LAST CDS_LOCATION C5G21
J 0
(-7350 4050);
PAINT MONO (-7350 4050);
DISPLAY INVISIBLE (-7350 4050);
FORCEPROP 2 LAST ROOM VDDQ_KLM_PWR_VR
J 0
(-7350 4050);
PAINT MONO (-7350 4050);
DISPLAY INVISIBLE (-7350 4050);
FORCEPROP 2 LAST BOM_COST MEM_VRD_PVDDQ_CD
J 0
(-7350 4050);
PAINT MONO (-7350 4050);
DISPLAY INVISIBLE (-7350 4050);
FORCEPROP 2 LAST CDS_LIB mstr_discrete
J 0
(-7400 3900);
PAINT MONO (-7400 3900);
DISPLAY INVISIBLE (-7400 3900);
FORCEPROP 1 LASTPIN (-7400 3800) $PN 2
J 0
(-7390 3780);
DISPLAY 0.787234 (-7390 3780);
PAINT ORANGE (-7390 3780);
DISPLAY INVISIBLE (-7390 3780);
FORCEPROP 1 LASTPIN (-7400 4000) $PN 1
J 0
(-7390 3980);
DISPLAY 0.787234 (-7390 3980);
PAINT ORANGE (-7390 3980);
DISPLAY INVISIBLE (-7390 3980);
FORCEADD CAP..1
(-7000 3900);
FORCEPROP 1 LAST VOLTAGE 4V
J 0
(-6950 3900);
DISPLAY 0.617021 (-6950 3900);
PAINT SKYBLUE (-6950 3900);
FORCEPROP 1 LAST MATERIAL X5R
J 0
(-6950 3800);
DISPLAY 0.617021 (-6950 3800);
PAINT SKYBLUE (-6950 3800);
FORCEPROP 1 LAST TOLERANCE 20%
J 0
(-6950 3850);
DISPLAY 0.617021 (-6950 3850);
PAINT SKYBLUE (-6950 3850);
FORCEPROP 1 LAST VALUE 100UF
J 0
(-6950 3950);
DISPLAY 0.617021 (-6950 3950);
PAINT SKYBLUE (-6950 3950);
FORCEPROP 1 LAST PACK_TYPE 0805
J 0
(-6950 3700);
DISPLAY 0.617021 (-6950 3700);
PAINT SKYBLUE (-6950 3700);
FORCEPROP 1 LAST PART_NUMBER 602433-112
J 0
(-6950 3750);
DISPLAY 0.617021 (-6950 3750);
PAINT BLUE (-6950 3750);
FORCEPROP 1 LAST LOCATION C5G22
J 0
(-6950 4000);
DISPLAY 0.617021 (-6950 4000);
PAINT AQUA (-6950 4000);
FORCEPROP 0 LAST SIDE_SKU 1S
J 0
(-7100 3975);
DISPLAY 1.021277 (-7100 3975);
PAINT ORANGE (-7100 3975);
FORCEPROP 1 LAST PATH I15
J 0
(-6950 4050);
DISPLAY 0.978723 (-6950 4050);
PAINT WHITE (-6950 4050);
DISPLAY INVISIBLE (-6950 4050);
FORCEPROP 0 LAST CDS_SEC 1
J 0
(-6950 4050);
PAINT MONO (-6950 4050);
DISPLAY INVISIBLE (-6950 4050);
FORCEPROP 0 LAST $SEC 1
J 0
(-6950 4050);
PAINT MONO (-6950 4050);
DISPLAY INVISIBLE (-6950 4050);
FORCEPROP 0 LAST CDS_LOCATION C5G22
J 0
(-6950 4050);
PAINT MONO (-6950 4050);
DISPLAY INVISIBLE (-6950 4050);
FORCEPROP 2 LAST ROOM VDDQ_KLM_PWR_VR
J 0
(-6950 4050);
PAINT MONO (-6950 4050);
DISPLAY INVISIBLE (-6950 4050);
FORCEPROP 2 LAST BOM_COST MEM_VRD_PVDDQ_CD
J 0
(-6950 4050);
PAINT MONO (-6950 4050);
DISPLAY INVISIBLE (-6950 4050);
FORCEPROP 2 LAST CDS_LIB mstr_discrete
J 0
(-7000 3900);
PAINT MONO (-7000 3900);
DISPLAY INVISIBLE (-7000 3900);
FORCEPROP 1 LASTPIN (-7000 3800) $PN 2
J 0
(-6990 3780);
DISPLAY 0.787234 (-6990 3780);
PAINT ORANGE (-6990 3780);
DISPLAY INVISIBLE (-6990 3780);
FORCEPROP 1 LASTPIN (-7000 4000) $PN 1
J 0
(-6990 3980);
DISPLAY 0.787234 (-6990 3980);
PAINT ORANGE (-6990 3980);
DISPLAY INVISIBLE (-6990 3980);
FORCEADD PVDDQ_ABC..1
(-7400 4325);
FORCEPROP 3 LASTPIN (-7400 4275) SIG_NAME PVDDQ_ABC\g
J 0
(-7390 4285);
DISPLAY 0.659574 (-7390 4285);
PAINT MONO (-7390 4285);
DISPLAY INVISIBLE (-7390 4285);
FORCEPROP 1 LAST HDL_POWER PVDDQ_ABC
J 1
(-7400 4375);
DISPLAY 0.872340 (-7400 4375);
PAINT GREEN (-7400 4375);
DISPLAY INVISIBLE (-7400 4375);
FORCEPROP 1 LAST BODY_TYPE PLUMBING
J 0
(-7445 4282);
DISPLAY 0.340426 (-7445 4282);
PAINT GREEN (-7445 4282);
DISPLAY INVISIBLE (-7445 4282);
FORCEPROP 1 LAST PATH I26
J 0
(-7350 4350);
DISPLAY 0.872340 (-7350 4350);
PAINT AQUA (-7350 4350);
DISPLAY INVISIBLE (-7350 4350);
FORCEPROP 2 LAST CDS_LIB mstr_symbols
J 0
(-7400 4325);
PAINT MONO (-7400 4325);
DISPLAY INVISIBLE (-7400 4325);
FORCEPROP 1 LAST VOLTAGE 1.2V
J 0
(-7445 4282);
DISPLAY 0.340426 (-7445 4282);
PAINT GREEN (-7445 4282);
DISPLAY INVISIBLE (-7445 4282);
FORCEPROP 2 LAST BOM_COST PROC_SOCKET 
J 0
(-7400 4425);
DISPLAY 1.446809 (-7400 4425);
PAINT MONO (-7400 4425);
DISPLAY INVISIBLE (-7400 4425);
FORCEPROP 2 LAST ROOM VDDQ_ABC_PWR_VR
J 0
(-7400 4425);
DISPLAY 1.936170 (-7400 4425);
PAINT ORANGE (-7400 4425);
DISPLAY INVISIBLE (-7400 4425);
FORCEADD GND..1
(-3150 1150);
FORCEPROP 3 LASTPIN (-3150 1200) SIG_NAME GND\g
J 0
(-3140 1210);
DISPLAY 0.659574 (-3140 1210);
PAINT MONO (-3140 1210);
DISPLAY INVISIBLE (-3140 1210);
FORCEPROP 1 LAST HDL_POWER GND
J 0
(-3150 1300);
DISPLAY 1.723404 (-3150 1300);
PAINT GREEN (-3150 1300);
DISPLAY INVISIBLE (-3150 1300);
FORCEPROP 1 LAST BODY_TYPE PLUMBING
J 0
(-3195 1107);
DISPLAY 0.340426 (-3195 1107);
PAINT GREEN (-3195 1107);
DISPLAY INVISIBLE (-3195 1107);
FORCEPROP 1 LAST PATH I27
J 0
(-3075 1150);
DISPLAY 0.872340 (-3075 1150);
PAINT AQUA (-3075 1150);
DISPLAY INVISIBLE (-3075 1150);
FORCEPROP 1 LAST SIZE 1B
J 0
(-3075 1100);
DISPLAY 1.723404 (-3075 1100);
PAINT GREEN (-3075 1100);
DISPLAY INVISIBLE (-3075 1100);
FORCEPROP 2 LAST BOM_COST PROC_VRD_VCCIN_CPU0
J 0
(-3525 1225);
DISPLAY 1.446809 (-3525 1225);
PAINT MONO (-3525 1225);
DISPLAY INVISIBLE (-3525 1225);
FORCEPROP 2 LAST ROOM VDDQ_ABC_PWR_VR
J 0
(-3700 1225);
DISPLAY 1.936170 (-3700 1225);
PAINT ORANGE (-3700 1225);
DISPLAY INVISIBLE (-3700 1225);
FORCEPROP 1 LAST VOLTAGE 0
J 0
(-3150 1150);
PAINT SKYBLUE (-3150 1150);
DISPLAY INVISIBLE (-3150 1150);
FORCEPROP 2 LAST CDS_LIB mstr_symbols
J 0
(-3150 1150);
PAINT MONO (-3150 1150);
DISPLAY INVISIBLE (-3150 1150);
FORCEADD PVDDQ_DEF..1
(-3150 1975);
FORCEPROP 3 LASTPIN (-3150 1925) SIG_NAME PVDDQ_DEF\g
J 0
(-3140 1935);
DISPLAY 0.659574 (-3140 1935);
PAINT MONO (-3140 1935);
DISPLAY INVISIBLE (-3140 1935);
FORCEPROP 1 LAST HDL_POWER PVDDQ_DEF
J 1
(-3150 2025);
DISPLAY 0.872340 (-3150 2025);
PAINT GREEN (-3150 2025);
DISPLAY INVISIBLE (-3150 2025);
FORCEPROP 1 LAST BODY_TYPE PLUMBING
J 0
(-3195 1932);
DISPLAY 0.340426 (-3195 1932);
PAINT GREEN (-3195 1932);
DISPLAY INVISIBLE (-3195 1932);
FORCEPROP 1 LAST PATH I29
J 0
(-3100 2000);
DISPLAY 0.872340 (-3100 2000);
PAINT AQUA (-3100 2000);
DISPLAY INVISIBLE (-3100 2000);
FORCEPROP 1 LAST VOLTAGE 1.2V
J 0
(-3195 1932);
DISPLAY 0.340426 (-3195 1932);
PAINT GREEN (-3195 1932);
DISPLAY INVISIBLE (-3195 1932);
FORCEPROP 2 LAST BOM_COST PROC_SOCKET 
J 0
(-3150 2075);
DISPLAY 1.446809 (-3150 2075);
PAINT MONO (-3150 2075);
DISPLAY INVISIBLE (-3150 2075);
FORCEPROP 2 LAST ROOM VDDQ_DEF_PWR_VR
J 0
(-3150 2075);
DISPLAY 1.936170 (-3150 2075);
PAINT ORANGE (-3150 2075);
DISPLAY INVISIBLE (-3150 2075);
FORCEPROP 2 LAST CDS_LIB mstr_symbols
J 0
(-3150 1975);
PAINT MONO (-3150 1975);
DISPLAY INVISIBLE (-3150 1975);
FORCEADD PVDDQ_ABC..1
(-7400 1925);
FORCEPROP 3 LASTPIN (-7400 1875) SIG_NAME PVDDQ_ABC\g
J 0
(-7390 1885);
DISPLAY 0.659574 (-7390 1885);
PAINT MONO (-7390 1885);
DISPLAY INVISIBLE (-7390 1885);
FORCEPROP 1 LAST HDL_POWER PVDDQ_ABC
J 1
(-7400 1975);
DISPLAY 0.872340 (-7400 1975);
PAINT GREEN (-7400 1975);
DISPLAY INVISIBLE (-7400 1975);
FORCEPROP 1 LAST BODY_TYPE PLUMBING
J 0
(-7445 1882);
DISPLAY 0.340426 (-7445 1882);
PAINT GREEN (-7445 1882);
DISPLAY INVISIBLE (-7445 1882);
FORCEPROP 1 LAST PATH I3
J 0
(-7350 1950);
DISPLAY 0.872340 (-7350 1950);
PAINT AQUA (-7350 1950);
DISPLAY INVISIBLE (-7350 1950);
FORCEPROP 1 LAST VOLTAGE 1.2V
J 0
(-7445 1882);
DISPLAY 0.340426 (-7445 1882);
PAINT GREEN (-7445 1882);
DISPLAY INVISIBLE (-7445 1882);
FORCEPROP 2 LAST BOM_COST PROC_SOCKET 
J 0
(-7400 2025);
DISPLAY 1.446809 (-7400 2025);
PAINT MONO (-7400 2025);
DISPLAY INVISIBLE (-7400 2025);
FORCEPROP 2 LAST ROOM VDDQ_ABC_PWR_VR
J 0
(-7400 2025);
DISPLAY 1.936170 (-7400 2025);
PAINT ORANGE (-7400 2025);
DISPLAY INVISIBLE (-7400 2025);
FORCEPROP 2 LAST CDS_LIB mstr_symbols
J 0
(-7400 1925);
PAINT MONO (-7400 1925);
DISPLAY INVISIBLE (-7400 1925);
FORCEADD GND..1
(-3150 2350);
FORCEPROP 3 LASTPIN (-3150 2400) SIG_NAME GND\g
J 0
(-3140 2410);
DISPLAY 0.659574 (-3140 2410);
PAINT MONO (-3140 2410);
DISPLAY INVISIBLE (-3140 2410);
FORCEPROP 1 LAST HDL_POWER GND
J 0
(-3150 2500);
DISPLAY 1.723404 (-3150 2500);
PAINT GREEN (-3150 2500);
DISPLAY INVISIBLE (-3150 2500);
FORCEPROP 1 LAST BODY_TYPE PLUMBING
J 0
(-3195 2307);
DISPLAY 0.340426 (-3195 2307);
PAINT GREEN (-3195 2307);
DISPLAY INVISIBLE (-3195 2307);
FORCEPROP 1 LAST PATH I33
J 0
(-3075 2350);
DISPLAY 0.872340 (-3075 2350);
PAINT AQUA (-3075 2350);
DISPLAY INVISIBLE (-3075 2350);
FORCEPROP 2 LAST CDS_LIB mstr_symbols
J 0
(-3150 2350);
PAINT MONO (-3150 2350);
DISPLAY INVISIBLE (-3150 2350);
FORCEPROP 1 LAST SIZE 1B
J 0
(-3075 2300);
DISPLAY 1.723404 (-3075 2300);
PAINT GREEN (-3075 2300);
DISPLAY INVISIBLE (-3075 2300);
FORCEPROP 2 LAST BOM_COST PROC_VRD_VCCIN_CPU0
J 0
(-3525 2425);
DISPLAY 1.446809 (-3525 2425);
PAINT MONO (-3525 2425);
DISPLAY INVISIBLE (-3525 2425);
FORCEPROP 2 LAST ROOM VDDQ_ABC_PWR_VR
J 0
(-3700 2425);
DISPLAY 1.936170 (-3700 2425);
PAINT ORANGE (-3700 2425);
DISPLAY INVISIBLE (-3700 2425);
FORCEPROP 1 LAST VOLTAGE 0
J 0
(-3150 2350);
PAINT SKYBLUE (-3150 2350);
DISPLAY INVISIBLE (-3150 2350);
FORCEADD PVDDQ_DEF..1
(-3150 3175);
FORCEPROP 3 LASTPIN (-3150 3125) SIG_NAME PVDDQ_DEF\g
J 0
(-3140 3135);
DISPLAY 0.659574 (-3140 3135);
PAINT MONO (-3140 3135);
DISPLAY INVISIBLE (-3140 3135);
FORCEPROP 1 LAST HDL_POWER PVDDQ_DEF
J 1
(-3150 3225);
DISPLAY 0.872340 (-3150 3225);
PAINT GREEN (-3150 3225);
DISPLAY INVISIBLE (-3150 3225);
FORCEPROP 1 LAST BODY_TYPE PLUMBING
J 0
(-3195 3132);
DISPLAY 0.340426 (-3195 3132);
PAINT GREEN (-3195 3132);
DISPLAY INVISIBLE (-3195 3132);
FORCEPROP 1 LAST PATH I35
J 0
(-3100 3200);
DISPLAY 0.872340 (-3100 3200);
PAINT AQUA (-3100 3200);
DISPLAY INVISIBLE (-3100 3200);
FORCEPROP 2 LAST CDS_LIB mstr_symbols
J 0
(-3150 3175);
PAINT MONO (-3150 3175);
DISPLAY INVISIBLE (-3150 3175);
FORCEPROP 1 LAST VOLTAGE 1.2V
J 0
(-3195 3132);
DISPLAY 0.340426 (-3195 3132);
PAINT GREEN (-3195 3132);
DISPLAY INVISIBLE (-3195 3132);
FORCEPROP 2 LAST BOM_COST PROC_SOCKET 
J 0
(-3150 3275);
DISPLAY 1.446809 (-3150 3275);
PAINT MONO (-3150 3275);
DISPLAY INVISIBLE (-3150 3275);
FORCEPROP 2 LAST ROOM VDDQ_DEF_PWR_VR
J 0
(-3150 3275);
DISPLAY 1.936170 (-3150 3275);
PAINT ORANGE (-3150 3275);
DISPLAY INVISIBLE (-3150 3275);
FORCEADD GND..1
(-3150 3400);
FORCEPROP 3 LASTPIN (-3150 3450) SIG_NAME GND\g
J 0
(-3140 3460);
DISPLAY 0.659574 (-3140 3460);
PAINT MONO (-3140 3460);
DISPLAY INVISIBLE (-3140 3460);
FORCEPROP 1 LAST HDL_POWER GND
J 0
(-3150 3550);
DISPLAY 1.723404 (-3150 3550);
PAINT GREEN (-3150 3550);
DISPLAY INVISIBLE (-3150 3550);
FORCEPROP 1 LAST BODY_TYPE PLUMBING
J 0
(-3195 3357);
DISPLAY 0.340426 (-3195 3357);
PAINT GREEN (-3195 3357);
DISPLAY INVISIBLE (-3195 3357);
FORCEPROP 1 LAST PATH I36
J 0
(-3075 3400);
DISPLAY 0.872340 (-3075 3400);
PAINT AQUA (-3075 3400);
DISPLAY INVISIBLE (-3075 3400);
FORCEPROP 2 LAST CDS_LIB mstr_symbols
J 0
(-3150 3400);
PAINT MONO (-3150 3400);
DISPLAY INVISIBLE (-3150 3400);
FORCEPROP 1 LAST SIZE 1B
J 0
(-3075 3350);
DISPLAY 1.723404 (-3075 3350);
PAINT GREEN (-3075 3350);
DISPLAY INVISIBLE (-3075 3350);
FORCEPROP 2 LAST BOM_COST PROC_VRD_VCCIN_CPU0
J 0
(-3525 3475);
DISPLAY 1.446809 (-3525 3475);
PAINT MONO (-3525 3475);
DISPLAY INVISIBLE (-3525 3475);
FORCEPROP 2 LAST ROOM VDDQ_ABC_PWR_VR
J 0
(-3700 3475);
DISPLAY 1.936170 (-3700 3475);
PAINT ORANGE (-3700 3475);
DISPLAY INVISIBLE (-3700 3475);
FORCEPROP 1 LAST VOLTAGE 0
J 0
(-3150 3400);
PAINT SKYBLUE (-3150 3400);
DISPLAY INVISIBLE (-3150 3400);
FORCEADD CAP..1
(-3150 3925);
FORCEPROP 1 LAST TOLERANCE 20%
J 0
(-3100 3875);
DISPLAY 0.617021 (-3100 3875);
PAINT SKYBLUE (-3100 3875);
FORCEPROP 1 LAST MATERIAL X5R
J 0
(-3100 3825);
DISPLAY 0.617021 (-3100 3825);
PAINT SKYBLUE (-3100 3825);
FORCEPROP 1 LAST PACK_TYPE 0805
J 0
(-3100 3725);
DISPLAY 0.617021 (-3100 3725);
PAINT SKYBLUE (-3100 3725);
FORCEPROP 1 LAST PART_NUMBER 602433-112
J 0
(-3100 3775);
DISPLAY 0.617021 (-3100 3775);
PAINT BLUE (-3100 3775);
FORCEPROP 1 LAST LOCATION C5G77
J 0
(-3100 4025);
DISPLAY 0.617021 (-3100 4025);
PAINT AQUA (-3100 4025);
FORCEPROP 1 LAST VALUE 100UF
J 0
(-3100 3975);
DISPLAY 0.617021 (-3100 3975);
PAINT SKYBLUE (-3100 3975);
FORCEPROP 1 LAST VOLTAGE 4V
J 0
(-3100 3925);
DISPLAY 0.617021 (-3100 3925);
PAINT SKYBLUE (-3100 3925);
FORCEPROP 0 LAST SIDE_SKU 1S
J 0
(-3250 4000);
DISPLAY 1.021277 (-3250 4000);
PAINT ORANGE (-3250 4000);
FORCEPROP 1 LAST PATH I37
J 0
(-3100 4075);
DISPLAY 0.978723 (-3100 4075);
PAINT WHITE (-3100 4075);
DISPLAY INVISIBLE (-3100 4075);
FORCEPROP 0 LAST CDS_SEC 1
J 0
(-3100 4075);
PAINT MONO (-3100 4075);
DISPLAY INVISIBLE (-3100 4075);
FORCEPROP 0 LAST $SEC 1
J 0
(-3100 4075);
PAINT MONO (-3100 4075);
DISPLAY INVISIBLE (-3100 4075);
FORCEPROP 0 LAST CDS_LOCATION C5G77
J 0
(-3100 4075);
PAINT MONO (-3100 4075);
DISPLAY INVISIBLE (-3100 4075);
FORCEPROP 2 LAST ROOM VDDQ_KLM_PWR_VR
J 0
(-3100 4075);
PAINT MONO (-3100 4075);
DISPLAY INVISIBLE (-3100 4075);
FORCEPROP 2 LAST BOM_COST MEM_VRD_PVDDQ_CD
J 0
(-3100 4075);
PAINT MONO (-3100 4075);
DISPLAY INVISIBLE (-3100 4075);
FORCEPROP 2 LAST CDS_LIB mstr_discrete
J 0
(-3150 3925);
PAINT MONO (-3150 3925);
DISPLAY INVISIBLE (-3150 3925);
FORCEPROP 1 LASTPIN (-3150 3825) $PN 2
J 0
(-3140 3805);
DISPLAY 0.787234 (-3140 3805);
PAINT ORANGE (-3140 3805);
DISPLAY INVISIBLE (-3140 3805);
FORCEPROP 1 LASTPIN (-3150 4025) $PN 1
J 0
(-3140 4005);
DISPLAY 0.787234 (-3140 4005);
PAINT ORANGE (-3140 4005);
DISPLAY INVISIBLE (-3140 4005);
FORCEADD CAP..1
(-2750 3925);
FORCEPROP 1 LAST LOCATION C5G78
J 0
(-2700 4025);
DISPLAY 0.617021 (-2700 4025);
PAINT AQUA (-2700 4025);
FORCEPROP 1 LAST VALUE 100UF
J 0
(-2700 3975);
DISPLAY 0.617021 (-2700 3975);
PAINT SKYBLUE (-2700 3975);
FORCEPROP 1 LAST TOLERANCE 20%
J 0
(-2700 3875);
DISPLAY 0.617021 (-2700 3875);
PAINT SKYBLUE (-2700 3875);
FORCEPROP 1 LAST VOLTAGE 4V
J 0
(-2700 3925);
DISPLAY 0.617021 (-2700 3925);
PAINT SKYBLUE (-2700 3925);
FORCEPROP 1 LAST MATERIAL X5R
J 0
(-2700 3825);
DISPLAY 0.617021 (-2700 3825);
PAINT SKYBLUE (-2700 3825);
FORCEPROP 1 LAST PACK_TYPE 0805
J 0
(-2700 3725);
DISPLAY 0.617021 (-2700 3725);
PAINT SKYBLUE (-2700 3725);
FORCEPROP 1 LAST PART_NUMBER 602433-112
J 0
(-2700 3775);
DISPLAY 0.617021 (-2700 3775);
PAINT BLUE (-2700 3775);
FORCEPROP 0 LAST SIDE_SKU 1S
J 0
(-2850 4000);
DISPLAY 1.021277 (-2850 4000);
PAINT ORANGE (-2850 4000);
FORCEPROP 1 LAST PATH I41
J 0
(-2700 4075);
DISPLAY 0.978723 (-2700 4075);
PAINT WHITE (-2700 4075);
DISPLAY INVISIBLE (-2700 4075);
FORCEPROP 0 LAST CDS_SEC 1
J 0
(-2700 4075);
PAINT MONO (-2700 4075);
DISPLAY INVISIBLE (-2700 4075);
FORCEPROP 0 LAST $SEC 1
J 0
(-2700 4075);
PAINT MONO (-2700 4075);
DISPLAY INVISIBLE (-2700 4075);
FORCEPROP 0 LAST CDS_LOCATION C5G78
J 0
(-2700 4075);
PAINT MONO (-2700 4075);
DISPLAY INVISIBLE (-2700 4075);
FORCEPROP 2 LAST CDS_LIB mstr_discrete
J 0
(-2750 3925);
PAINT MONO (-2750 3925);
DISPLAY INVISIBLE (-2750 3925);
FORCEPROP 2 LAST BOM_COST MEM_VRD_PVDDQ_CD
J 0
(-2700 4075);
PAINT MONO (-2700 4075);
DISPLAY INVISIBLE (-2700 4075);
FORCEPROP 2 LAST ROOM VDDQ_KLM_PWR_VR
J 0
(-2700 4075);
PAINT MONO (-2700 4075);
DISPLAY INVISIBLE (-2700 4075);
FORCEPROP 1 LASTPIN (-2750 3825) $PN 2
J 0
(-2740 3805);
DISPLAY 0.787234 (-2740 3805);
PAINT ORANGE (-2740 3805);
DISPLAY INVISIBLE (-2740 3805);
FORCEPROP 1 LASTPIN (-2750 4025) $PN 1
J 0
(-2740 4005);
DISPLAY 0.787234 (-2740 4005);
PAINT ORANGE (-2740 4005);
DISPLAY INVISIBLE (-2740 4005);
FORCEADD PVDDQ_DEF..1
(-3150 4350);
FORCEPROP 3 LASTPIN (-3150 4300) SIG_NAME PVDDQ_DEF\g
J 0
(-3140 4310);
DISPLAY 0.659574 (-3140 4310);
PAINT MONO (-3140 4310);
DISPLAY INVISIBLE (-3140 4310);
FORCEPROP 1 LAST HDL_POWER PVDDQ_DEF
J 1
(-3150 4400);
DISPLAY 0.872340 (-3150 4400);
PAINT GREEN (-3150 4400);
DISPLAY INVISIBLE (-3150 4400);
FORCEPROP 1 LAST BODY_TYPE PLUMBING
J 0
(-3195 4307);
DISPLAY 0.340426 (-3195 4307);
PAINT GREEN (-3195 4307);
DISPLAY INVISIBLE (-3195 4307);
FORCEPROP 1 LAST PATH I50
J 0
(-3100 4375);
DISPLAY 0.872340 (-3100 4375);
PAINT AQUA (-3100 4375);
DISPLAY INVISIBLE (-3100 4375);
FORCEPROP 2 LAST CDS_LIB mstr_symbols
J 0
(-3150 4350);
PAINT MONO (-3150 4350);
DISPLAY INVISIBLE (-3150 4350);
FORCEPROP 1 LAST VOLTAGE 1.2V
J 0
(-3195 4307);
DISPLAY 0.340426 (-3195 4307);
PAINT GREEN (-3195 4307);
DISPLAY INVISIBLE (-3195 4307);
FORCEPROP 2 LAST BOM_COST PROC_SOCKET 
J 0
(-3150 4450);
DISPLAY 1.446809 (-3150 4450);
PAINT MONO (-3150 4450);
DISPLAY INVISIBLE (-3150 4450);
FORCEPROP 2 LAST ROOM VDDQ_DEF_PWR_VR
J 0
(-3150 4450);
DISPLAY 1.936170 (-3150 4450);
PAINT ORANGE (-3150 4450);
DISPLAY INVISIBLE (-3150 4450);
FORCEADD CAP_A..1
(-7400 2775);
FORCEPROP 1 LAST TOLERANCE 20%
J 0
(-7350 2725);
DISPLAY 0.617021 (-7350 2725);
PAINT SKYBLUE (-7350 2725);
FORCEPROP 1 LAST PACK_TYPE 0603V
J 0
(-7350 2575);
DISPLAY 0.617021 (-7350 2575);
PAINT SKYBLUE (-7350 2575);
FORCEPROP 1 LAST MATERIAL X6S
J 0
(-7350 2675);
DISPLAY 0.617021 (-7350 2675);
PAINT SKYBLUE (-7350 2675);
FORCEPROP 1 LAST VOLTAGE 4V
J 0
(-7350 2775);
DISPLAY 0.617021 (-7350 2775);
PAINT SKYBLUE (-7350 2775);
FORCEPROP 1 LAST PART_NUMBER E15431-004
J 0
(-7350 2625);
DISPLAY 0.617021 (-7350 2625);
PAINT BLUE (-7350 2625);
FORCEPROP 1 LAST VALUE 22.0UF
J 0
(-7350 2825);
DISPLAY 0.617021 (-7350 2825);
PAINT SKYBLUE (-7350 2825);
FORCEPROP 1 LAST LOCATION C5G41
J 0
(-7350 2875);
DISPLAY 0.617021 (-7350 2875);
PAINT AQUA (-7350 2875);
FORCEPROP 0 LAST SIDE_SKU 1S
J 0
(-7525 2825);
DISPLAY 1.021277 (-7525 2825);
PAINT ORANGE (-7525 2825);
FORCEPROP 1 LASTPIN (-7400 2675) $PN 2
J 0
(-7390 2655);
DISPLAY 0.787234 (-7390 2655);
PAINT ORANGE (-7390 2655);
DISPLAY INVISIBLE (-7390 2655);
FORCEPROP 1 LASTPIN (-7400 2875) $PN 1
J 0
(-7390 2855);
DISPLAY 0.787234 (-7390 2855);
PAINT ORANGE (-7390 2855);
DISPLAY INVISIBLE (-7390 2855);
FORCEPROP 0 LAST ROOM PVDDQ_KLM
J 0
(-7350 2975);
DISPLAY 1.021277 (-7350 2975);
PAINT ORANGE (-7350 2975);
DISPLAY INVISIBLE (-7350 2975);
FORCEPROP 1 LAST PATH I53
J 0
(-7350 2925);
DISPLAY 0.978723 (-7350 2925);
PAINT WHITE (-7350 2925);
DISPLAY INVISIBLE (-7350 2925);
FORCEPROP 2 LAST CDS_LIB dev_discrete
J 0
(-7400 2775);
PAINT MONO (-7400 2775);
DISPLAY INVISIBLE (-7400 2775);
FORCEADD CAP_A..1
(-7100 2775);
FORCEPROP 1 LAST VALUE 22.0UF
J 0
(-7050 2825);
DISPLAY 0.617021 (-7050 2825);
PAINT SKYBLUE (-7050 2825);
FORCEPROP 1 LAST LOCATION C5G42
J 0
(-7050 2875);
DISPLAY 0.617021 (-7050 2875);
PAINT AQUA (-7050 2875);
FORCEPROP 1 LAST PACK_TYPE 0603V
J 0
(-7050 2575);
DISPLAY 0.617021 (-7050 2575);
PAINT SKYBLUE (-7050 2575);
FORCEPROP 1 LAST MATERIAL X6S
J 0
(-7050 2675);
DISPLAY 0.617021 (-7050 2675);
PAINT SKYBLUE (-7050 2675);
FORCEPROP 1 LAST VOLTAGE 4V
J 0
(-7050 2775);
DISPLAY 0.617021 (-7050 2775);
PAINT SKYBLUE (-7050 2775);
FORCEPROP 1 LAST TOLERANCE 20%
J 0
(-7050 2725);
DISPLAY 0.617021 (-7050 2725);
PAINT SKYBLUE (-7050 2725);
FORCEPROP 1 LAST PART_NUMBER E15431-004
J 0
(-7050 2625);
DISPLAY 0.617021 (-7050 2625);
PAINT BLUE (-7050 2625);
FORCEPROP 0 LAST SIDE_SKU 1S
J 0
(-7225 2825);
DISPLAY 1.021277 (-7225 2825);
PAINT ORANGE (-7225 2825);
FORCEPROP 1 LASTPIN (-7100 2675) $PN 2
J 0
(-7090 2655);
DISPLAY 0.787234 (-7090 2655);
PAINT ORANGE (-7090 2655);
DISPLAY INVISIBLE (-7090 2655);
FORCEPROP 1 LASTPIN (-7100 2875) $PN 1
J 0
(-7090 2855);
DISPLAY 0.787234 (-7090 2855);
PAINT ORANGE (-7090 2855);
DISPLAY INVISIBLE (-7090 2855);
FORCEPROP 0 LAST ROOM PVDDQ_KLM
J 0
(-7050 2975);
DISPLAY 1.021277 (-7050 2975);
PAINT ORANGE (-7050 2975);
DISPLAY INVISIBLE (-7050 2975);
FORCEPROP 1 LAST PATH I54
J 0
(-7050 2925);
DISPLAY 0.978723 (-7050 2925);
PAINT WHITE (-7050 2925);
DISPLAY INVISIBLE (-7050 2925);
FORCEPROP 2 LAST CDS_LIB dev_discrete
J 0
(-7100 2775);
PAINT MONO (-7100 2775);
DISPLAY INVISIBLE (-7100 2775);
FORCEADD CAP_A..1
(-6450 2775);
FORCEPROP 1 LAST LOCATION C5G44
J 0
(-6400 2875);
DISPLAY 0.617021 (-6400 2875);
PAINT AQUA (-6400 2875);
FORCEPROP 1 LAST TOLERANCE 20%
J 0
(-6400 2725);
DISPLAY 0.617021 (-6400 2725);
PAINT SKYBLUE (-6400 2725);
FORCEPROP 1 LAST VALUE 22.0UF
J 0
(-6400 2825);
DISPLAY 0.617021 (-6400 2825);
PAINT SKYBLUE (-6400 2825);
FORCEPROP 1 LAST PART_NUMBER E15431-004
J 0
(-6400 2625);
DISPLAY 0.617021 (-6400 2625);
PAINT BLUE (-6400 2625);
FORCEPROP 1 LAST VOLTAGE 4V
J 0
(-6400 2775);
DISPLAY 0.617021 (-6400 2775);
PAINT SKYBLUE (-6400 2775);
FORCEPROP 1 LAST MATERIAL X6S
J 0
(-6400 2675);
DISPLAY 0.617021 (-6400 2675);
PAINT SKYBLUE (-6400 2675);
FORCEPROP 1 LAST PACK_TYPE 0603V
J 0
(-6400 2575);
DISPLAY 0.617021 (-6400 2575);
PAINT SKYBLUE (-6400 2575);
FORCEPROP 0 LAST SIDE_SKU 1S
J 0
(-6575 2825);
DISPLAY 1.021277 (-6575 2825);
PAINT ORANGE (-6575 2825);
FORCEPROP 1 LASTPIN (-6450 2675) $PN 2
J 0
(-6440 2655);
DISPLAY 0.787234 (-6440 2655);
PAINT ORANGE (-6440 2655);
DISPLAY INVISIBLE (-6440 2655);
FORCEPROP 1 LASTPIN (-6450 2875) $PN 1
J 0
(-6440 2855);
DISPLAY 0.787234 (-6440 2855);
PAINT ORANGE (-6440 2855);
DISPLAY INVISIBLE (-6440 2855);
FORCEPROP 0 LAST ROOM PVDDQ_KLM
J 0
(-6400 2975);
DISPLAY 1.021277 (-6400 2975);
PAINT ORANGE (-6400 2975);
DISPLAY INVISIBLE (-6400 2975);
FORCEPROP 1 LAST PATH I55
J 0
(-6400 2925);
DISPLAY 0.978723 (-6400 2925);
PAINT WHITE (-6400 2925);
DISPLAY INVISIBLE (-6400 2925);
FORCEPROP 2 LAST CDS_LIB dev_discrete
J 0
(-6450 2775);
PAINT MONO (-6450 2775);
DISPLAY INVISIBLE (-6450 2775);
FORCEADD CAP_A..1
(-6800 2775);
FORCEPROP 1 LAST MATERIAL X6S
J 0
(-6750 2675);
DISPLAY 0.617021 (-6750 2675);
PAINT SKYBLUE (-6750 2675);
FORCEPROP 1 LAST TOLERANCE 20%
J 0
(-6750 2725);
DISPLAY 0.617021 (-6750 2725);
PAINT SKYBLUE (-6750 2725);
FORCEPROP 1 LAST VALUE 22.0UF
J 0
(-6750 2825);
DISPLAY 0.617021 (-6750 2825);
PAINT SKYBLUE (-6750 2825);
FORCEPROP 1 LAST LOCATION C5G43
J 0
(-6750 2875);
DISPLAY 0.617021 (-6750 2875);
PAINT AQUA (-6750 2875);
FORCEPROP 1 LAST PACK_TYPE 0603V
J 0
(-6750 2575);
DISPLAY 0.617021 (-6750 2575);
PAINT SKYBLUE (-6750 2575);
FORCEPROP 1 LAST VOLTAGE 4V
J 0
(-6750 2775);
DISPLAY 0.617021 (-6750 2775);
PAINT SKYBLUE (-6750 2775);
FORCEPROP 1 LAST PART_NUMBER E15431-004
J 0
(-6750 2625);
DISPLAY 0.617021 (-6750 2625);
PAINT BLUE (-6750 2625);
FORCEPROP 0 LAST SIDE_SKU 1S
J 0
(-6925 2825);
DISPLAY 1.021277 (-6925 2825);
PAINT ORANGE (-6925 2825);
FORCEPROP 1 LASTPIN (-6800 2675) $PN 2
J 0
(-6790 2655);
DISPLAY 0.787234 (-6790 2655);
PAINT ORANGE (-6790 2655);
DISPLAY INVISIBLE (-6790 2655);
FORCEPROP 1 LASTPIN (-6800 2875) $PN 1
J 0
(-6790 2855);
DISPLAY 0.787234 (-6790 2855);
PAINT ORANGE (-6790 2855);
DISPLAY INVISIBLE (-6790 2855);
FORCEPROP 0 LAST ROOM PVDDQ_KLM
J 0
(-6750 2975);
DISPLAY 1.021277 (-6750 2975);
PAINT ORANGE (-6750 2975);
DISPLAY INVISIBLE (-6750 2975);
FORCEPROP 1 LAST PATH I56
J 0
(-6750 2925);
DISPLAY 0.978723 (-6750 2925);
PAINT WHITE (-6750 2925);
DISPLAY INVISIBLE (-6750 2925);
FORCEPROP 2 LAST CDS_LIB dev_discrete
J 0
(-6800 2775);
PAINT MONO (-6800 2775);
DISPLAY INVISIBLE (-6800 2775);
FORCEADD CAP_A..1
(-5250 2775);
FORCEPROP 1 LAST LOCATION C5G48
J 0
(-5200 2875);
DISPLAY 0.617021 (-5200 2875);
PAINT AQUA (-5200 2875);
FORCEPROP 1 LAST PACK_TYPE 0603V
J 0
(-5200 2575);
DISPLAY 0.617021 (-5200 2575);
PAINT SKYBLUE (-5200 2575);
FORCEPROP 1 LAST MATERIAL X6S
J 0
(-5200 2675);
DISPLAY 0.617021 (-5200 2675);
PAINT SKYBLUE (-5200 2675);
FORCEPROP 1 LAST VOLTAGE 4V
J 0
(-5200 2775);
DISPLAY 0.617021 (-5200 2775);
PAINT SKYBLUE (-5200 2775);
FORCEPROP 1 LAST TOLERANCE 20%
J 0
(-5200 2725);
DISPLAY 0.617021 (-5200 2725);
PAINT SKYBLUE (-5200 2725);
FORCEPROP 1 LAST PART_NUMBER E15431-004
J 0
(-5200 2625);
DISPLAY 0.617021 (-5200 2625);
PAINT BLUE (-5200 2625);
FORCEPROP 1 LAST VALUE 22.0UF
J 0
(-5200 2825);
DISPLAY 0.617021 (-5200 2825);
PAINT SKYBLUE (-5200 2825);
FORCEPROP 0 LAST SIDE_SKU 1S
J 0
(-5375 2825);
DISPLAY 1.021277 (-5375 2825);
PAINT ORANGE (-5375 2825);
FORCEPROP 1 LASTPIN (-5250 2675) $PN 2
J 0
(-5240 2655);
DISPLAY 0.787234 (-5240 2655);
PAINT ORANGE (-5240 2655);
DISPLAY INVISIBLE (-5240 2655);
FORCEPROP 1 LASTPIN (-5250 2875) $PN 1
J 0
(-5240 2855);
DISPLAY 0.787234 (-5240 2855);
PAINT ORANGE (-5240 2855);
DISPLAY INVISIBLE (-5240 2855);
FORCEPROP 0 LAST ROOM PVDDQ_KLM
J 0
(-5200 2975);
DISPLAY 1.021277 (-5200 2975);
PAINT ORANGE (-5200 2975);
DISPLAY INVISIBLE (-5200 2975);
FORCEPROP 1 LAST PATH I57
J 0
(-5200 2925);
DISPLAY 0.978723 (-5200 2925);
PAINT WHITE (-5200 2925);
DISPLAY INVISIBLE (-5200 2925);
FORCEPROP 2 LAST CDS_LIB dev_discrete
J 0
(-5250 2775);
PAINT MONO (-5250 2775);
DISPLAY INVISIBLE (-5250 2775);
FORCEADD CAP_A..1
(-5550 2775);
FORCEPROP 1 LAST MATERIAL X6S
J 0
(-5500 2675);
DISPLAY 0.617021 (-5500 2675);
PAINT SKYBLUE (-5500 2675);
FORCEPROP 1 LAST PACK_TYPE 0603V
J 0
(-5500 2575);
DISPLAY 0.617021 (-5500 2575);
PAINT SKYBLUE (-5500 2575);
FORCEPROP 1 LAST PART_NUMBER E15431-004
J 0
(-5500 2625);
DISPLAY 0.617021 (-5500 2625);
PAINT BLUE (-5500 2625);
FORCEPROP 1 LAST TOLERANCE 20%
J 0
(-5500 2725);
DISPLAY 0.617021 (-5500 2725);
PAINT SKYBLUE (-5500 2725);
FORCEPROP 1 LAST VOLTAGE 4V
J 0
(-5500 2775);
DISPLAY 0.617021 (-5500 2775);
PAINT SKYBLUE (-5500 2775);
FORCEPROP 1 LAST VALUE 22.0UF
J 0
(-5500 2825);
DISPLAY 0.617021 (-5500 2825);
PAINT SKYBLUE (-5500 2825);
FORCEPROP 1 LAST LOCATION C5G47
J 0
(-5500 2875);
DISPLAY 0.617021 (-5500 2875);
PAINT AQUA (-5500 2875);
FORCEPROP 0 LAST SIDE_SKU 1S
J 0
(-5675 2825);
DISPLAY 1.021277 (-5675 2825);
PAINT ORANGE (-5675 2825);
FORCEPROP 1 LASTPIN (-5550 2675) $PN 2
J 0
(-5540 2655);
DISPLAY 0.787234 (-5540 2655);
PAINT ORANGE (-5540 2655);
DISPLAY INVISIBLE (-5540 2655);
FORCEPROP 1 LASTPIN (-5550 2875) $PN 1
J 0
(-5540 2855);
DISPLAY 0.787234 (-5540 2855);
PAINT ORANGE (-5540 2855);
DISPLAY INVISIBLE (-5540 2855);
FORCEPROP 0 LAST ROOM PVDDQ_KLM
J 0
(-5500 2975);
DISPLAY 1.021277 (-5500 2975);
PAINT ORANGE (-5500 2975);
DISPLAY INVISIBLE (-5500 2975);
FORCEPROP 1 LAST PATH I58
J 0
(-5500 2925);
DISPLAY 0.978723 (-5500 2925);
PAINT WHITE (-5500 2925);
DISPLAY INVISIBLE (-5500 2925);
FORCEPROP 2 LAST CDS_LIB dev_discrete
J 0
(-5550 2775);
PAINT MONO (-5550 2775);
DISPLAY INVISIBLE (-5550 2775);
FORCEADD CAP_A..1
(-5850 2775);
FORCEPROP 1 LAST LOCATION C5G46
J 0
(-5800 2875);
DISPLAY 0.617021 (-5800 2875);
PAINT AQUA (-5800 2875);
FORCEPROP 1 LAST VALUE 22.0UF
J 0
(-5800 2825);
DISPLAY 0.617021 (-5800 2825);
PAINT SKYBLUE (-5800 2825);
FORCEPROP 1 LAST VOLTAGE 4V
J 0
(-5800 2775);
DISPLAY 0.617021 (-5800 2775);
PAINT SKYBLUE (-5800 2775);
FORCEPROP 1 LAST TOLERANCE 20%
J 0
(-5800 2725);
DISPLAY 0.617021 (-5800 2725);
PAINT SKYBLUE (-5800 2725);
FORCEPROP 1 LAST MATERIAL X6S
J 0
(-5800 2675);
DISPLAY 0.617021 (-5800 2675);
PAINT SKYBLUE (-5800 2675);
FORCEPROP 1 LAST PART_NUMBER E15431-004
J 0
(-5800 2625);
DISPLAY 0.617021 (-5800 2625);
PAINT BLUE (-5800 2625);
FORCEPROP 1 LAST PACK_TYPE 0603V
J 0
(-5800 2575);
DISPLAY 0.617021 (-5800 2575);
PAINT SKYBLUE (-5800 2575);
FORCEPROP 0 LAST SIDE_SKU 1S
J 0
(-5975 2825);
DISPLAY 1.021277 (-5975 2825);
PAINT ORANGE (-5975 2825);
FORCEPROP 1 LASTPIN (-5850 2675) $PN 2
J 0
(-5840 2655);
DISPLAY 0.787234 (-5840 2655);
PAINT ORANGE (-5840 2655);
DISPLAY INVISIBLE (-5840 2655);
FORCEPROP 1 LASTPIN (-5850 2875) $PN 1
J 0
(-5840 2855);
DISPLAY 0.787234 (-5840 2855);
PAINT ORANGE (-5840 2855);
DISPLAY INVISIBLE (-5840 2855);
FORCEPROP 0 LAST ROOM PVDDQ_KLM
J 0
(-5800 2975);
DISPLAY 1.021277 (-5800 2975);
PAINT ORANGE (-5800 2975);
DISPLAY INVISIBLE (-5800 2975);
FORCEPROP 1 LAST PATH I59
J 0
(-5800 2925);
DISPLAY 0.978723 (-5800 2925);
PAINT WHITE (-5800 2925);
DISPLAY INVISIBLE (-5800 2925);
FORCEPROP 2 LAST CDS_LIB dev_discrete
J 0
(-5850 2775);
PAINT MONO (-5850 2775);
DISPLAY INVISIBLE (-5850 2775);
FORCEADD CAP_A..1
(-6150 2775);
FORCEPROP 1 LAST LOCATION C5G45
J 0
(-6100 2875);
DISPLAY 0.617021 (-6100 2875);
PAINT AQUA (-6100 2875);
FORCEPROP 1 LAST VALUE 22.0UF
J 0
(-6100 2825);
DISPLAY 0.617021 (-6100 2825);
PAINT SKYBLUE (-6100 2825);
FORCEPROP 1 LAST TOLERANCE 20%
J 0
(-6100 2725);
DISPLAY 0.617021 (-6100 2725);
PAINT SKYBLUE (-6100 2725);
FORCEPROP 1 LAST PACK_TYPE 0603V
J 0
(-6100 2575);
DISPLAY 0.617021 (-6100 2575);
PAINT SKYBLUE (-6100 2575);
FORCEPROP 1 LAST MATERIAL X6S
J 0
(-6100 2675);
DISPLAY 0.617021 (-6100 2675);
PAINT SKYBLUE (-6100 2675);
FORCEPROP 1 LAST VOLTAGE 4V
J 0
(-6100 2775);
DISPLAY 0.617021 (-6100 2775);
PAINT SKYBLUE (-6100 2775);
FORCEPROP 1 LAST PART_NUMBER E15431-004
J 0
(-6100 2625);
DISPLAY 0.617021 (-6100 2625);
PAINT BLUE (-6100 2625);
FORCEPROP 0 LAST SIDE_SKU 1S
J 0
(-6275 2825);
DISPLAY 1.021277 (-6275 2825);
PAINT ORANGE (-6275 2825);
FORCEPROP 1 LASTPIN (-6150 2675) $PN 2
J 0
(-6140 2655);
DISPLAY 0.787234 (-6140 2655);
PAINT ORANGE (-6140 2655);
DISPLAY INVISIBLE (-6140 2655);
FORCEPROP 1 LASTPIN (-6150 2875) $PN 1
J 0
(-6140 2855);
DISPLAY 0.787234 (-6140 2855);
PAINT ORANGE (-6140 2855);
DISPLAY INVISIBLE (-6140 2855);
FORCEPROP 0 LAST ROOM PVDDQ_KLM
J 0
(-6100 2975);
DISPLAY 1.021277 (-6100 2975);
PAINT ORANGE (-6100 2975);
DISPLAY INVISIBLE (-6100 2975);
FORCEPROP 1 LAST PATH I60
J 0
(-6100 2925);
DISPLAY 0.978723 (-6100 2925);
PAINT WHITE (-6100 2925);
DISPLAY INVISIBLE (-6100 2925);
FORCEPROP 2 LAST CDS_LIB dev_discrete
J 0
(-6150 2775);
PAINT MONO (-6150 2775);
DISPLAY INVISIBLE (-6150 2775);
FORCEADD CAP_A..1
(-4950 2775);
FORCEPROP 1 LAST LOCATION C5G49
J 0
(-4900 2875);
DISPLAY 0.617021 (-4900 2875);
PAINT AQUA (-4900 2875);
FORCEPROP 1 LAST PACK_TYPE 0603V
J 0
(-4900 2575);
DISPLAY 0.617021 (-4900 2575);
PAINT SKYBLUE (-4900 2575);
FORCEPROP 1 LAST MATERIAL X6S
J 0
(-4900 2675);
DISPLAY 0.617021 (-4900 2675);
PAINT SKYBLUE (-4900 2675);
FORCEPROP 1 LAST VOLTAGE 4V
J 0
(-4900 2775);
DISPLAY 0.617021 (-4900 2775);
PAINT SKYBLUE (-4900 2775);
FORCEPROP 1 LAST TOLERANCE 20%
J 0
(-4900 2725);
DISPLAY 0.617021 (-4900 2725);
PAINT SKYBLUE (-4900 2725);
FORCEPROP 1 LAST PART_NUMBER E15431-004
J 0
(-4900 2625);
DISPLAY 0.617021 (-4900 2625);
PAINT BLUE (-4900 2625);
FORCEPROP 1 LAST VALUE 22.0UF
J 0
(-4900 2825);
DISPLAY 0.617021 (-4900 2825);
PAINT SKYBLUE (-4900 2825);
FORCEPROP 0 LAST SIDE_SKU 1S
J 0
(-5075 2825);
DISPLAY 1.021277 (-5075 2825);
PAINT ORANGE (-5075 2825);
FORCEPROP 1 LASTPIN (-4950 2675) $PN 2
J 0
(-4940 2655);
DISPLAY 0.787234 (-4940 2655);
PAINT ORANGE (-4940 2655);
DISPLAY INVISIBLE (-4940 2655);
FORCEPROP 1 LASTPIN (-4950 2875) $PN 1
J 0
(-4940 2855);
DISPLAY 0.787234 (-4940 2855);
PAINT ORANGE (-4940 2855);
DISPLAY INVISIBLE (-4940 2855);
FORCEPROP 0 LAST ROOM PVDDQ_KLM
J 0
(-4900 2975);
DISPLAY 1.021277 (-4900 2975);
PAINT ORANGE (-4900 2975);
DISPLAY INVISIBLE (-4900 2975);
FORCEPROP 1 LAST PATH I61
J 0
(-4900 2925);
DISPLAY 0.978723 (-4900 2925);
PAINT WHITE (-4900 2925);
DISPLAY INVISIBLE (-4900 2925);
FORCEPROP 2 LAST CDS_LIB dev_discrete
J 0
(-4950 2775);
PAINT MONO (-4950 2775);
DISPLAY INVISIBLE (-4950 2775);
FORCEADD CAP_A..1
(-6150 1600);
FORCEPROP 1 LAST PACK_TYPE 0603V
J 0
(-6100 1400);
DISPLAY 0.617021 (-6100 1400);
PAINT SKYBLUE (-6100 1400);
FORCEPROP 1 LAST PART_NUMBER E15431-004
J 0
(-6100 1450);
DISPLAY 0.617021 (-6100 1450);
PAINT BLUE (-6100 1450);
FORCEPROP 1 LAST TOLERANCE 20%
J 0
(-6100 1550);
DISPLAY 0.617021 (-6100 1550);
PAINT SKYBLUE (-6100 1550);
FORCEPROP 1 LAST VALUE 22.0UF
J 0
(-6100 1650);
DISPLAY 0.617021 (-6100 1650);
PAINT SKYBLUE (-6100 1650);
FORCEPROP 1 LAST MATERIAL X6S
J 0
(-6100 1500);
DISPLAY 0.617021 (-6100 1500);
PAINT SKYBLUE (-6100 1500);
FORCEPROP 1 LAST LOCATION C5G54
J 0
(-6100 1700);
DISPLAY 0.617021 (-6100 1700);
PAINT AQUA (-6100 1700);
FORCEPROP 1 LAST VOLTAGE 4V
J 0
(-6100 1600);
DISPLAY 0.617021 (-6100 1600);
PAINT SKYBLUE (-6100 1600);
FORCEPROP 0 LAST SIDE_SKU 1S
J 0
(-6275 1650);
DISPLAY 1.021277 (-6275 1650);
PAINT ORANGE (-6275 1650);
FORCEPROP 1 LASTPIN (-6150 1500) $PN 2
J 0
(-6140 1480);
DISPLAY 0.787234 (-6140 1480);
PAINT ORANGE (-6140 1480);
DISPLAY INVISIBLE (-6140 1480);
FORCEPROP 1 LASTPIN (-6150 1700) $PN 1
J 0
(-6140 1680);
DISPLAY 0.787234 (-6140 1680);
PAINT ORANGE (-6140 1680);
DISPLAY INVISIBLE (-6140 1680);
FORCEPROP 0 LAST ROOM PVDDQ_KLM
J 0
(-6100 1800);
DISPLAY 1.021277 (-6100 1800);
PAINT ORANGE (-6100 1800);
DISPLAY INVISIBLE (-6100 1800);
FORCEPROP 1 LAST PATH I62
J 0
(-6100 1750);
DISPLAY 0.978723 (-6100 1750);
PAINT WHITE (-6100 1750);
DISPLAY INVISIBLE (-6100 1750);
FORCEPROP 2 LAST CDS_LIB dev_discrete
J 0
(-6150 1600);
PAINT MONO (-6150 1600);
DISPLAY INVISIBLE (-6150 1600);
FORCEADD CAP_A..1
(-4950 1600);
FORCEPROP 1 LAST PACK_TYPE 0603V
J 0
(-4900 1400);
DISPLAY 0.617021 (-4900 1400);
PAINT SKYBLUE (-4900 1400);
FORCEPROP 1 LAST MATERIAL X6S
J 0
(-4900 1500);
DISPLAY 0.617021 (-4900 1500);
PAINT SKYBLUE (-4900 1500);
FORCEPROP 1 LAST VOLTAGE 4V
J 0
(-4900 1600);
DISPLAY 0.617021 (-4900 1600);
PAINT SKYBLUE (-4900 1600);
FORCEPROP 1 LAST TOLERANCE 20%
J 0
(-4900 1550);
DISPLAY 0.617021 (-4900 1550);
PAINT SKYBLUE (-4900 1550);
FORCEPROP 1 LAST PART_NUMBER E15431-004
J 0
(-4900 1450);
DISPLAY 0.617021 (-4900 1450);
PAINT BLUE (-4900 1450);
FORCEPROP 1 LAST VALUE 22.0UF
J 0
(-4900 1650);
DISPLAY 0.617021 (-4900 1650);
PAINT SKYBLUE (-4900 1650);
FORCEPROP 1 LAST LOCATION C5G58
J 0
(-4900 1700);
DISPLAY 0.617021 (-4900 1700);
PAINT AQUA (-4900 1700);
FORCEPROP 0 LAST SIDE_SKU 1S
J 0
(-5075 1650);
DISPLAY 1.021277 (-5075 1650);
PAINT ORANGE (-5075 1650);
FORCEPROP 1 LASTPIN (-4950 1500) $PN 2
J 0
(-4940 1480);
DISPLAY 0.787234 (-4940 1480);
PAINT ORANGE (-4940 1480);
DISPLAY INVISIBLE (-4940 1480);
FORCEPROP 1 LASTPIN (-4950 1700) $PN 1
J 0
(-4940 1680);
DISPLAY 0.787234 (-4940 1680);
PAINT ORANGE (-4940 1680);
DISPLAY INVISIBLE (-4940 1680);
FORCEPROP 0 LAST ROOM PVDDQ_KLM
J 0
(-4900 1800);
DISPLAY 1.021277 (-4900 1800);
PAINT ORANGE (-4900 1800);
DISPLAY INVISIBLE (-4900 1800);
FORCEPROP 1 LAST PATH I63
J 0
(-4900 1750);
DISPLAY 0.978723 (-4900 1750);
PAINT WHITE (-4900 1750);
DISPLAY INVISIBLE (-4900 1750);
FORCEPROP 2 LAST CDS_LIB dev_discrete
J 0
(-4950 1600);
PAINT MONO (-4950 1600);
DISPLAY INVISIBLE (-4950 1600);
FORCEADD CAP_A..1
(-5250 1600);
FORCEPROP 1 LAST PACK_TYPE 0603V
J 0
(-5200 1400);
DISPLAY 0.617021 (-5200 1400);
PAINT SKYBLUE (-5200 1400);
FORCEPROP 1 LAST MATERIAL X6S
J 0
(-5200 1500);
DISPLAY 0.617021 (-5200 1500);
PAINT SKYBLUE (-5200 1500);
FORCEPROP 1 LAST VOLTAGE 4V
J 0
(-5200 1600);
DISPLAY 0.617021 (-5200 1600);
PAINT SKYBLUE (-5200 1600);
FORCEPROP 1 LAST TOLERANCE 20%
J 0
(-5200 1550);
DISPLAY 0.617021 (-5200 1550);
PAINT SKYBLUE (-5200 1550);
FORCEPROP 1 LAST PART_NUMBER E15431-004
J 0
(-5200 1450);
DISPLAY 0.617021 (-5200 1450);
PAINT BLUE (-5200 1450);
FORCEPROP 1 LAST VALUE 22.0UF
J 0
(-5200 1650);
DISPLAY 0.617021 (-5200 1650);
PAINT SKYBLUE (-5200 1650);
FORCEPROP 1 LAST LOCATION C5G57
J 0
(-5200 1700);
DISPLAY 0.617021 (-5200 1700);
PAINT AQUA (-5200 1700);
FORCEPROP 0 LAST SIDE_SKU 1S
J 0
(-5375 1650);
DISPLAY 1.021277 (-5375 1650);
PAINT ORANGE (-5375 1650);
FORCEPROP 1 LASTPIN (-5250 1500) $PN 2
J 0
(-5240 1480);
DISPLAY 0.787234 (-5240 1480);
PAINT ORANGE (-5240 1480);
DISPLAY INVISIBLE (-5240 1480);
FORCEPROP 1 LASTPIN (-5250 1700) $PN 1
J 0
(-5240 1680);
DISPLAY 0.787234 (-5240 1680);
PAINT ORANGE (-5240 1680);
DISPLAY INVISIBLE (-5240 1680);
FORCEPROP 0 LAST ROOM PVDDQ_KLM
J 0
(-5200 1800);
DISPLAY 1.021277 (-5200 1800);
PAINT ORANGE (-5200 1800);
DISPLAY INVISIBLE (-5200 1800);
FORCEPROP 1 LAST PATH I64
J 0
(-5200 1750);
DISPLAY 0.978723 (-5200 1750);
PAINT WHITE (-5200 1750);
DISPLAY INVISIBLE (-5200 1750);
FORCEPROP 2 LAST CDS_LIB dev_discrete
J 0
(-5250 1600);
PAINT MONO (-5250 1600);
DISPLAY INVISIBLE (-5250 1600);
FORCEADD CAP_A..1
(-5550 1600);
FORCEPROP 1 LAST VALUE 22.0UF
J 0
(-5500 1650);
DISPLAY 0.617021 (-5500 1650);
PAINT SKYBLUE (-5500 1650);
FORCEPROP 1 LAST PACK_TYPE 0603V
J 0
(-5500 1400);
DISPLAY 0.617021 (-5500 1400);
PAINT SKYBLUE (-5500 1400);
FORCEPROP 1 LAST MATERIAL X6S
J 0
(-5500 1500);
DISPLAY 0.617021 (-5500 1500);
PAINT SKYBLUE (-5500 1500);
FORCEPROP 1 LAST VOLTAGE 4V
J 0
(-5500 1600);
DISPLAY 0.617021 (-5500 1600);
PAINT SKYBLUE (-5500 1600);
FORCEPROP 1 LAST TOLERANCE 20%
J 0
(-5500 1550);
DISPLAY 0.617021 (-5500 1550);
PAINT SKYBLUE (-5500 1550);
FORCEPROP 1 LAST PART_NUMBER E15431-004
J 0
(-5500 1450);
DISPLAY 0.617021 (-5500 1450);
PAINT BLUE (-5500 1450);
FORCEPROP 1 LAST LOCATION C5G56
J 0
(-5500 1700);
DISPLAY 0.617021 (-5500 1700);
PAINT AQUA (-5500 1700);
FORCEPROP 0 LAST SIDE_SKU 1S
J 0
(-5675 1650);
DISPLAY 1.021277 (-5675 1650);
PAINT ORANGE (-5675 1650);
FORCEPROP 1 LASTPIN (-5550 1500) $PN 2
J 0
(-5540 1480);
DISPLAY 0.787234 (-5540 1480);
PAINT ORANGE (-5540 1480);
DISPLAY INVISIBLE (-5540 1480);
FORCEPROP 1 LASTPIN (-5550 1700) $PN 1
J 0
(-5540 1680);
DISPLAY 0.787234 (-5540 1680);
PAINT ORANGE (-5540 1680);
DISPLAY INVISIBLE (-5540 1680);
FORCEPROP 0 LAST ROOM PVDDQ_KLM
J 0
(-5500 1800);
DISPLAY 1.021277 (-5500 1800);
PAINT ORANGE (-5500 1800);
DISPLAY INVISIBLE (-5500 1800);
FORCEPROP 1 LAST PATH I65
J 0
(-5500 1750);
DISPLAY 0.978723 (-5500 1750);
PAINT WHITE (-5500 1750);
DISPLAY INVISIBLE (-5500 1750);
FORCEPROP 2 LAST CDS_LIB dev_discrete
J 0
(-5550 1600);
PAINT MONO (-5550 1600);
DISPLAY INVISIBLE (-5550 1600);
FORCEADD CAP_A..1
(-5850 1600);
FORCEPROP 1 LAST PACK_TYPE 0603V
J 0
(-5800 1400);
DISPLAY 0.617021 (-5800 1400);
PAINT SKYBLUE (-5800 1400);
FORCEPROP 1 LAST MATERIAL X6S
J 0
(-5800 1500);
DISPLAY 0.617021 (-5800 1500);
PAINT SKYBLUE (-5800 1500);
FORCEPROP 1 LAST VOLTAGE 4V
J 0
(-5800 1600);
DISPLAY 0.617021 (-5800 1600);
PAINT SKYBLUE (-5800 1600);
FORCEPROP 1 LAST TOLERANCE 20%
J 0
(-5800 1550);
DISPLAY 0.617021 (-5800 1550);
PAINT SKYBLUE (-5800 1550);
FORCEPROP 1 LAST LOCATION C5G55
J 0
(-5800 1700);
DISPLAY 0.617021 (-5800 1700);
PAINT AQUA (-5800 1700);
FORCEPROP 1 LAST PART_NUMBER E15431-004
J 0
(-5800 1450);
DISPLAY 0.617021 (-5800 1450);
PAINT BLUE (-5800 1450);
FORCEPROP 1 LAST VALUE 22.0UF
J 0
(-5800 1650);
DISPLAY 0.617021 (-5800 1650);
PAINT SKYBLUE (-5800 1650);
FORCEPROP 0 LAST SIDE_SKU 1S
J 0
(-5975 1650);
DISPLAY 1.021277 (-5975 1650);
PAINT ORANGE (-5975 1650);
FORCEPROP 1 LASTPIN (-5850 1500) $PN 2
J 0
(-5840 1480);
DISPLAY 0.787234 (-5840 1480);
PAINT ORANGE (-5840 1480);
DISPLAY INVISIBLE (-5840 1480);
FORCEPROP 1 LASTPIN (-5850 1700) $PN 1
J 0
(-5840 1680);
DISPLAY 0.787234 (-5840 1680);
PAINT ORANGE (-5840 1680);
DISPLAY INVISIBLE (-5840 1680);
FORCEPROP 0 LAST ROOM PVDDQ_KLM
J 0
(-5800 1800);
DISPLAY 1.021277 (-5800 1800);
PAINT ORANGE (-5800 1800);
DISPLAY INVISIBLE (-5800 1800);
FORCEPROP 1 LAST PATH I66
J 0
(-5800 1750);
DISPLAY 0.978723 (-5800 1750);
PAINT WHITE (-5800 1750);
DISPLAY INVISIBLE (-5800 1750);
FORCEPROP 2 LAST CDS_LIB dev_discrete
J 0
(-5850 1600);
PAINT MONO (-5850 1600);
DISPLAY INVISIBLE (-5850 1600);
FORCEADD CAP_A..1
(-6450 1600);
FORCEPROP 1 LAST TOLERANCE 20%
J 0
(-6400 1550);
DISPLAY 0.617021 (-6400 1550);
PAINT SKYBLUE (-6400 1550);
FORCEPROP 1 LAST PACK_TYPE 0603V
J 0
(-6400 1400);
DISPLAY 0.617021 (-6400 1400);
PAINT SKYBLUE (-6400 1400);
FORCEPROP 1 LAST VOLTAGE 4V
J 0
(-6400 1600);
DISPLAY 0.617021 (-6400 1600);
PAINT SKYBLUE (-6400 1600);
FORCEPROP 1 LAST MATERIAL X6S
J 0
(-6400 1500);
DISPLAY 0.617021 (-6400 1500);
PAINT SKYBLUE (-6400 1500);
FORCEPROP 1 LAST PART_NUMBER E15431-004
J 0
(-6400 1450);
DISPLAY 0.617021 (-6400 1450);
PAINT BLUE (-6400 1450);
FORCEPROP 1 LAST VALUE 22.0UF
J 0
(-6400 1650);
DISPLAY 0.617021 (-6400 1650);
PAINT SKYBLUE (-6400 1650);
FORCEPROP 1 LAST LOCATION C5G53
J 0
(-6400 1700);
DISPLAY 0.617021 (-6400 1700);
PAINT AQUA (-6400 1700);
FORCEPROP 0 LAST SIDE_SKU 1S
J 0
(-6575 1650);
DISPLAY 1.021277 (-6575 1650);
PAINT ORANGE (-6575 1650);
FORCEPROP 1 LASTPIN (-6450 1500) $PN 2
J 0
(-6440 1480);
DISPLAY 0.787234 (-6440 1480);
PAINT ORANGE (-6440 1480);
DISPLAY INVISIBLE (-6440 1480);
FORCEPROP 1 LASTPIN (-6450 1700) $PN 1
J 0
(-6440 1680);
DISPLAY 0.787234 (-6440 1680);
PAINT ORANGE (-6440 1680);
DISPLAY INVISIBLE (-6440 1680);
FORCEPROP 0 LAST ROOM PVDDQ_KLM
J 0
(-6400 1800);
DISPLAY 1.021277 (-6400 1800);
PAINT ORANGE (-6400 1800);
DISPLAY INVISIBLE (-6400 1800);
FORCEPROP 1 LAST PATH I67
J 0
(-6400 1750);
DISPLAY 0.978723 (-6400 1750);
PAINT WHITE (-6400 1750);
DISPLAY INVISIBLE (-6400 1750);
FORCEPROP 2 LAST CDS_LIB dev_discrete
J 0
(-6450 1600);
PAINT MONO (-6450 1600);
DISPLAY INVISIBLE (-6450 1600);
FORCEADD CAP_A..1
(-6800 1600);
FORCEPROP 1 LAST PACK_TYPE 0603V
J 0
(-6750 1400);
DISPLAY 0.617021 (-6750 1400);
PAINT SKYBLUE (-6750 1400);
FORCEPROP 1 LAST MATERIAL X6S
J 0
(-6750 1500);
DISPLAY 0.617021 (-6750 1500);
PAINT SKYBLUE (-6750 1500);
FORCEPROP 1 LAST VOLTAGE 4V
J 0
(-6750 1600);
DISPLAY 0.617021 (-6750 1600);
PAINT SKYBLUE (-6750 1600);
FORCEPROP 1 LAST LOCATION C5G52
J 0
(-6750 1700);
DISPLAY 0.617021 (-6750 1700);
PAINT AQUA (-6750 1700);
FORCEPROP 1 LAST PART_NUMBER E15431-004
J 0
(-6750 1450);
DISPLAY 0.617021 (-6750 1450);
PAINT BLUE (-6750 1450);
FORCEPROP 1 LAST TOLERANCE 20%
J 0
(-6750 1550);
DISPLAY 0.617021 (-6750 1550);
PAINT SKYBLUE (-6750 1550);
FORCEPROP 1 LAST VALUE 22.0UF
J 0
(-6750 1650);
DISPLAY 0.617021 (-6750 1650);
PAINT SKYBLUE (-6750 1650);
FORCEPROP 0 LAST SIDE_SKU 1S
J 0
(-6925 1650);
DISPLAY 1.021277 (-6925 1650);
PAINT ORANGE (-6925 1650);
FORCEPROP 1 LASTPIN (-6800 1500) $PN 2
J 0
(-6790 1480);
DISPLAY 0.787234 (-6790 1480);
PAINT ORANGE (-6790 1480);
DISPLAY INVISIBLE (-6790 1480);
FORCEPROP 1 LASTPIN (-6800 1700) $PN 1
J 0
(-6790 1680);
DISPLAY 0.787234 (-6790 1680);
PAINT ORANGE (-6790 1680);
DISPLAY INVISIBLE (-6790 1680);
FORCEPROP 0 LAST ROOM PVDDQ_KLM
J 0
(-6750 1800);
DISPLAY 1.021277 (-6750 1800);
PAINT ORANGE (-6750 1800);
DISPLAY INVISIBLE (-6750 1800);
FORCEPROP 1 LAST PATH I68
J 0
(-6750 1750);
DISPLAY 0.978723 (-6750 1750);
PAINT WHITE (-6750 1750);
DISPLAY INVISIBLE (-6750 1750);
FORCEPROP 2 LAST CDS_LIB dev_discrete
J 0
(-6800 1600);
PAINT MONO (-6800 1600);
DISPLAY INVISIBLE (-6800 1600);
FORCEADD CAP_A..1
(-7100 1600);
FORCEPROP 1 LAST LOCATION C5G51
J 0
(-7050 1700);
DISPLAY 0.617021 (-7050 1700);
PAINT AQUA (-7050 1700);
FORCEPROP 1 LAST MATERIAL X6S
J 0
(-7050 1500);
DISPLAY 0.617021 (-7050 1500);
PAINT SKYBLUE (-7050 1500);
FORCEPROP 1 LAST PACK_TYPE 0603V
J 0
(-7050 1400);
DISPLAY 0.617021 (-7050 1400);
PAINT SKYBLUE (-7050 1400);
FORCEPROP 1 LAST PART_NUMBER E15431-004
J 0
(-7050 1450);
DISPLAY 0.617021 (-7050 1450);
PAINT BLUE (-7050 1450);
FORCEPROP 1 LAST TOLERANCE 20%
J 0
(-7050 1550);
DISPLAY 0.617021 (-7050 1550);
PAINT SKYBLUE (-7050 1550);
FORCEPROP 1 LAST VOLTAGE 4V
J 0
(-7050 1600);
DISPLAY 0.617021 (-7050 1600);
PAINT SKYBLUE (-7050 1600);
FORCEPROP 1 LAST VALUE 22.0UF
J 0
(-7050 1650);
DISPLAY 0.617021 (-7050 1650);
PAINT SKYBLUE (-7050 1650);
FORCEPROP 0 LAST SIDE_SKU 1S
J 0
(-7225 1650);
DISPLAY 1.021277 (-7225 1650);
PAINT ORANGE (-7225 1650);
FORCEPROP 1 LASTPIN (-7100 1500) $PN 2
J 0
(-7090 1480);
DISPLAY 0.787234 (-7090 1480);
PAINT ORANGE (-7090 1480);
DISPLAY INVISIBLE (-7090 1480);
FORCEPROP 1 LASTPIN (-7100 1700) $PN 1
J 0
(-7090 1680);
DISPLAY 0.787234 (-7090 1680);
PAINT ORANGE (-7090 1680);
DISPLAY INVISIBLE (-7090 1680);
FORCEPROP 0 LAST ROOM PVDDQ_KLM
J 0
(-7050 1800);
DISPLAY 1.021277 (-7050 1800);
PAINT ORANGE (-7050 1800);
DISPLAY INVISIBLE (-7050 1800);
FORCEPROP 1 LAST PATH I69
J 0
(-7050 1750);
DISPLAY 0.978723 (-7050 1750);
PAINT WHITE (-7050 1750);
DISPLAY INVISIBLE (-7050 1750);
FORCEPROP 2 LAST CDS_LIB dev_discrete
J 0
(-7100 1600);
PAINT MONO (-7100 1600);
DISPLAY INVISIBLE (-7100 1600);
FORCEADD GND..1
(-7400 2275);
FORCEPROP 3 LASTPIN (-7400 2325) SIG_NAME GND\g
J 0
(-7390 2335);
DISPLAY 0.659574 (-7390 2335);
PAINT MONO (-7390 2335);
DISPLAY INVISIBLE (-7390 2335);
FORCEPROP 1 LAST HDL_POWER GND
J 0
(-7400 2425);
DISPLAY 1.723404 (-7400 2425);
PAINT GREEN (-7400 2425);
DISPLAY INVISIBLE (-7400 2425);
FORCEPROP 1 LAST BODY_TYPE PLUMBING
J 0
(-7445 2232);
DISPLAY 0.340426 (-7445 2232);
PAINT GREEN (-7445 2232);
DISPLAY INVISIBLE (-7445 2232);
FORCEPROP 1 LAST PATH I7
J 0
(-7325 2275);
DISPLAY 0.872340 (-7325 2275);
PAINT AQUA (-7325 2275);
DISPLAY INVISIBLE (-7325 2275);
FORCEPROP 2 LAST CDS_LIB mstr_symbols
J 0
(-7400 2275);
PAINT MONO (-7400 2275);
DISPLAY INVISIBLE (-7400 2275);
FORCEPROP 1 LAST SIZE 1B
J 0
(-7325 2225);
DISPLAY 1.723404 (-7325 2225);
PAINT GREEN (-7325 2225);
DISPLAY INVISIBLE (-7325 2225);
FORCEPROP 2 LAST BOM_COST PROC_VRD_VCCIN_CPU0
J 0
(-7775 2350);
DISPLAY 1.446809 (-7775 2350);
PAINT MONO (-7775 2350);
DISPLAY INVISIBLE (-7775 2350);
FORCEPROP 2 LAST ROOM VDDQ_ABC_PWR_VR
J 0
(-7950 2350);
DISPLAY 1.936170 (-7950 2350);
PAINT ORANGE (-7950 2350);
DISPLAY INVISIBLE (-7950 2350);
FORCEPROP 1 LAST VOLTAGE 0
J 0
(-7400 2275);
PAINT SKYBLUE (-7400 2275);
DISPLAY INVISIBLE (-7400 2275);
FORCEADD CAP_A..1
(-7400 1600);
FORCEPROP 1 LAST LOCATION C5G50
J 0
(-7350 1700);
DISPLAY 0.617021 (-7350 1700);
PAINT AQUA (-7350 1700);
FORCEPROP 1 LAST PACK_TYPE 0603V
J 0
(-7350 1400);
DISPLAY 0.617021 (-7350 1400);
PAINT SKYBLUE (-7350 1400);
FORCEPROP 1 LAST MATERIAL X6S
J 0
(-7350 1500);
DISPLAY 0.617021 (-7350 1500);
PAINT SKYBLUE (-7350 1500);
FORCEPROP 1 LAST TOLERANCE 20%
J 0
(-7350 1550);
DISPLAY 0.617021 (-7350 1550);
PAINT SKYBLUE (-7350 1550);
FORCEPROP 1 LAST VALUE 22.0UF
J 0
(-7350 1650);
DISPLAY 0.617021 (-7350 1650);
PAINT SKYBLUE (-7350 1650);
FORCEPROP 1 LAST VOLTAGE 4V
J 0
(-7350 1600);
DISPLAY 0.617021 (-7350 1600);
PAINT SKYBLUE (-7350 1600);
FORCEPROP 1 LAST PART_NUMBER E15431-004
J 0
(-7350 1450);
DISPLAY 0.617021 (-7350 1450);
PAINT BLUE (-7350 1450);
FORCEPROP 0 LAST SIDE_SKU 1S
J 0
(-7525 1650);
DISPLAY 1.021277 (-7525 1650);
PAINT ORANGE (-7525 1650);
FORCEPROP 1 LASTPIN (-7400 1500) $PN 2
J 0
(-7390 1480);
DISPLAY 0.787234 (-7390 1480);
PAINT ORANGE (-7390 1480);
DISPLAY INVISIBLE (-7390 1480);
FORCEPROP 1 LASTPIN (-7400 1700) $PN 1
J 0
(-7390 1680);
DISPLAY 0.787234 (-7390 1680);
PAINT ORANGE (-7390 1680);
DISPLAY INVISIBLE (-7390 1680);
FORCEPROP 0 LAST ROOM PVDDQ_KLM
J 0
(-7350 1800);
DISPLAY 1.021277 (-7350 1800);
PAINT ORANGE (-7350 1800);
DISPLAY INVISIBLE (-7350 1800);
FORCEPROP 1 LAST PATH I70
J 0
(-7350 1750);
DISPLAY 0.978723 (-7350 1750);
PAINT WHITE (-7350 1750);
DISPLAY INVISIBLE (-7350 1750);
FORCEPROP 2 LAST CDS_LIB dev_discrete
J 0
(-7400 1600);
PAINT MONO (-7400 1600);
DISPLAY INVISIBLE (-7400 1600);
FORCEADD CAP_A..1
(-700 2850);
FORCEPROP 1 LAST PACK_TYPE 0603V
J 0
(-650 2650);
DISPLAY 0.617021 (-650 2650);
PAINT SKYBLUE (-650 2650);
FORCEPROP 1 LAST MATERIAL X6S
J 0
(-650 2750);
DISPLAY 0.617021 (-650 2750);
PAINT SKYBLUE (-650 2750);
FORCEPROP 1 LAST VOLTAGE 4V
J 0
(-650 2850);
DISPLAY 0.617021 (-650 2850);
PAINT SKYBLUE (-650 2850);
FORCEPROP 1 LAST TOLERANCE 20%
J 0
(-650 2800);
DISPLAY 0.617021 (-650 2800);
PAINT SKYBLUE (-650 2800);
FORCEPROP 1 LAST PART_NUMBER E15431-004
J 0
(-650 2700);
DISPLAY 0.617021 (-650 2700);
PAINT BLUE (-650 2700);
FORCEPROP 1 LAST VALUE 22.0UF
J 0
(-650 2900);
DISPLAY 0.617021 (-650 2900);
PAINT SKYBLUE (-650 2900);
FORCEPROP 1 LAST LOCATION C5G67
J 0
(-650 2950);
DISPLAY 0.617021 (-650 2950);
PAINT AQUA (-650 2950);
FORCEPROP 0 LAST SIDE_SKU 1S
J 0
(-825 2900);
DISPLAY 1.021277 (-825 2900);
PAINT ORANGE (-825 2900);
FORCEPROP 1 LASTPIN (-700 2750) $PN 2
J 0
(-690 2730);
DISPLAY 0.787234 (-690 2730);
PAINT ORANGE (-690 2730);
DISPLAY INVISIBLE (-690 2730);
FORCEPROP 1 LASTPIN (-700 2950) $PN 1
J 0
(-690 2930);
DISPLAY 0.787234 (-690 2930);
PAINT ORANGE (-690 2930);
DISPLAY INVISIBLE (-690 2930);
FORCEPROP 2 LAST CDS_LIB dev_discrete
J 0
(-700 2850);
PAINT MONO (-700 2850);
DISPLAY INVISIBLE (-700 2850);
FORCEPROP 1 LAST PATH I71
J 0
(-650 3000);
DISPLAY 0.978723 (-650 3000);
PAINT WHITE (-650 3000);
DISPLAY INVISIBLE (-650 3000);
FORCEPROP 0 LAST ROOM PVDDQ_KLM
J 0
(-650 3050);
DISPLAY 1.021277 (-650 3050);
PAINT ORANGE (-650 3050);
DISPLAY INVISIBLE (-650 3050);
FORCEADD CAP_A..1
(-1000 2850);
FORCEPROP 1 LAST PACK_TYPE 0603V
J 0
(-950 2650);
DISPLAY 0.617021 (-950 2650);
PAINT SKYBLUE (-950 2650);
FORCEPROP 1 LAST MATERIAL X6S
J 0
(-950 2750);
DISPLAY 0.617021 (-950 2750);
PAINT SKYBLUE (-950 2750);
FORCEPROP 1 LAST VOLTAGE 4V
J 0
(-950 2850);
DISPLAY 0.617021 (-950 2850);
PAINT SKYBLUE (-950 2850);
FORCEPROP 1 LAST TOLERANCE 20%
J 0
(-950 2800);
DISPLAY 0.617021 (-950 2800);
PAINT SKYBLUE (-950 2800);
FORCEPROP 1 LAST PART_NUMBER E15431-004
J 0
(-950 2700);
DISPLAY 0.617021 (-950 2700);
PAINT BLUE (-950 2700);
FORCEPROP 1 LAST VALUE 22.0UF
J 0
(-950 2900);
DISPLAY 0.617021 (-950 2900);
PAINT SKYBLUE (-950 2900);
FORCEPROP 1 LAST LOCATION C5G66
J 0
(-950 2950);
DISPLAY 0.617021 (-950 2950);
PAINT AQUA (-950 2950);
FORCEPROP 0 LAST SIDE_SKU 1S
J 0
(-1125 2900);
DISPLAY 1.021277 (-1125 2900);
PAINT ORANGE (-1125 2900);
FORCEPROP 1 LASTPIN (-1000 2750) $PN 2
J 0
(-990 2730);
DISPLAY 0.787234 (-990 2730);
PAINT ORANGE (-990 2730);
DISPLAY INVISIBLE (-990 2730);
FORCEPROP 1 LASTPIN (-1000 2950) $PN 1
J 0
(-990 2930);
DISPLAY 0.787234 (-990 2930);
PAINT ORANGE (-990 2930);
DISPLAY INVISIBLE (-990 2930);
FORCEPROP 2 LAST CDS_LIB dev_discrete
J 0
(-1000 2850);
PAINT MONO (-1000 2850);
DISPLAY INVISIBLE (-1000 2850);
FORCEPROP 1 LAST PATH I72
J 0
(-950 3000);
DISPLAY 0.978723 (-950 3000);
PAINT WHITE (-950 3000);
DISPLAY INVISIBLE (-950 3000);
FORCEPROP 0 LAST ROOM PVDDQ_KLM
J 0
(-950 3050);
DISPLAY 1.021277 (-950 3050);
PAINT ORANGE (-950 3050);
DISPLAY INVISIBLE (-950 3050);
FORCEADD CAP_A..1
(-1300 2850);
FORCEPROP 1 LAST VALUE 22.0UF
J 0
(-1250 2900);
DISPLAY 0.617021 (-1250 2900);
PAINT SKYBLUE (-1250 2900);
FORCEPROP 1 LAST PACK_TYPE 0603V
J 0
(-1250 2650);
DISPLAY 0.617021 (-1250 2650);
PAINT SKYBLUE (-1250 2650);
FORCEPROP 1 LAST MATERIAL X6S
J 0
(-1250 2750);
DISPLAY 0.617021 (-1250 2750);
PAINT SKYBLUE (-1250 2750);
FORCEPROP 1 LAST VOLTAGE 4V
J 0
(-1250 2850);
DISPLAY 0.617021 (-1250 2850);
PAINT SKYBLUE (-1250 2850);
FORCEPROP 1 LAST TOLERANCE 20%
J 0
(-1250 2800);
DISPLAY 0.617021 (-1250 2800);
PAINT SKYBLUE (-1250 2800);
FORCEPROP 1 LAST PART_NUMBER E15431-004
J 0
(-1250 2700);
DISPLAY 0.617021 (-1250 2700);
PAINT BLUE (-1250 2700);
FORCEPROP 1 LAST LOCATION C5G65
J 0
(-1250 2950);
DISPLAY 0.617021 (-1250 2950);
PAINT AQUA (-1250 2950);
FORCEPROP 0 LAST SIDE_SKU 1S
J 0
(-1425 2900);
DISPLAY 1.021277 (-1425 2900);
PAINT ORANGE (-1425 2900);
FORCEPROP 1 LASTPIN (-1300 2750) $PN 2
J 0
(-1290 2730);
DISPLAY 0.787234 (-1290 2730);
PAINT ORANGE (-1290 2730);
DISPLAY INVISIBLE (-1290 2730);
FORCEPROP 1 LASTPIN (-1300 2950) $PN 1
J 0
(-1290 2930);
DISPLAY 0.787234 (-1290 2930);
PAINT ORANGE (-1290 2930);
DISPLAY INVISIBLE (-1290 2930);
FORCEPROP 2 LAST CDS_LIB dev_discrete
J 0
(-1300 2850);
PAINT MONO (-1300 2850);
DISPLAY INVISIBLE (-1300 2850);
FORCEPROP 1 LAST PATH I73
J 0
(-1250 3000);
DISPLAY 0.978723 (-1250 3000);
PAINT WHITE (-1250 3000);
DISPLAY INVISIBLE (-1250 3000);
FORCEPROP 0 LAST ROOM PVDDQ_KLM
J 0
(-1250 3050);
DISPLAY 1.021277 (-1250 3050);
PAINT ORANGE (-1250 3050);
DISPLAY INVISIBLE (-1250 3050);
FORCEADD CAP_A..1
(-1600 2850);
FORCEPROP 1 LAST PACK_TYPE 0603V
J 0
(-1550 2650);
DISPLAY 0.617021 (-1550 2650);
PAINT SKYBLUE (-1550 2650);
FORCEPROP 1 LAST MATERIAL X6S
J 0
(-1550 2750);
DISPLAY 0.617021 (-1550 2750);
PAINT SKYBLUE (-1550 2750);
FORCEPROP 1 LAST VOLTAGE 4V
J 0
(-1550 2850);
DISPLAY 0.617021 (-1550 2850);
PAINT SKYBLUE (-1550 2850);
FORCEPROP 1 LAST TOLERANCE 20%
J 0
(-1550 2800);
DISPLAY 0.617021 (-1550 2800);
PAINT SKYBLUE (-1550 2800);
FORCEPROP 1 LAST PART_NUMBER E15431-004
J 0
(-1550 2700);
DISPLAY 0.617021 (-1550 2700);
PAINT BLUE (-1550 2700);
FORCEPROP 1 LAST VALUE 22.0UF
J 0
(-1550 2900);
DISPLAY 0.617021 (-1550 2900);
PAINT SKYBLUE (-1550 2900);
FORCEPROP 1 LAST LOCATION C5G64
J 0
(-1550 2950);
DISPLAY 0.617021 (-1550 2950);
PAINT AQUA (-1550 2950);
FORCEPROP 0 LAST SIDE_SKU 1S
J 0
(-1725 2900);
DISPLAY 1.021277 (-1725 2900);
PAINT ORANGE (-1725 2900);
FORCEPROP 1 LASTPIN (-1600 2750) $PN 2
J 0
(-1590 2730);
DISPLAY 0.787234 (-1590 2730);
PAINT ORANGE (-1590 2730);
DISPLAY INVISIBLE (-1590 2730);
FORCEPROP 1 LASTPIN (-1600 2950) $PN 1
J 0
(-1590 2930);
DISPLAY 0.787234 (-1590 2930);
PAINT ORANGE (-1590 2930);
DISPLAY INVISIBLE (-1590 2930);
FORCEPROP 2 LAST CDS_LIB dev_discrete
J 0
(-1600 2850);
PAINT MONO (-1600 2850);
DISPLAY INVISIBLE (-1600 2850);
FORCEPROP 1 LAST PATH I74
J 0
(-1550 3000);
DISPLAY 0.978723 (-1550 3000);
PAINT WHITE (-1550 3000);
DISPLAY INVISIBLE (-1550 3000);
FORCEPROP 0 LAST ROOM PVDDQ_KLM
J 0
(-1550 3050);
DISPLAY 1.021277 (-1550 3050);
PAINT ORANGE (-1550 3050);
DISPLAY INVISIBLE (-1550 3050);
FORCEADD CAP_A..1
(-1900 2850);
FORCEPROP 1 LAST PACK_TYPE 0603V
J 0
(-1850 2650);
DISPLAY 0.617021 (-1850 2650);
PAINT SKYBLUE (-1850 2650);
FORCEPROP 1 LAST MATERIAL X6S
J 0
(-1850 2750);
DISPLAY 0.617021 (-1850 2750);
PAINT SKYBLUE (-1850 2750);
FORCEPROP 1 LAST VOLTAGE 4V
J 0
(-1850 2850);
DISPLAY 0.617021 (-1850 2850);
PAINT SKYBLUE (-1850 2850);
FORCEPROP 1 LAST TOLERANCE 20%
J 0
(-1850 2800);
DISPLAY 0.617021 (-1850 2800);
PAINT SKYBLUE (-1850 2800);
FORCEPROP 1 LAST PART_NUMBER E15431-004
J 0
(-1850 2700);
DISPLAY 0.617021 (-1850 2700);
PAINT BLUE (-1850 2700);
FORCEPROP 1 LAST VALUE 22.0UF
J 0
(-1850 2900);
DISPLAY 0.617021 (-1850 2900);
PAINT SKYBLUE (-1850 2900);
FORCEPROP 1 LAST LOCATION C5G63
J 0
(-1850 2950);
DISPLAY 0.617021 (-1850 2950);
PAINT AQUA (-1850 2950);
FORCEPROP 0 LAST SIDE_SKU 1S
J 0
(-2025 2900);
DISPLAY 1.021277 (-2025 2900);
PAINT ORANGE (-2025 2900);
FORCEPROP 1 LASTPIN (-1900 2750) $PN 2
J 0
(-1890 2730);
DISPLAY 0.787234 (-1890 2730);
PAINT ORANGE (-1890 2730);
DISPLAY INVISIBLE (-1890 2730);
FORCEPROP 1 LASTPIN (-1900 2950) $PN 1
J 0
(-1890 2930);
DISPLAY 0.787234 (-1890 2930);
PAINT ORANGE (-1890 2930);
DISPLAY INVISIBLE (-1890 2930);
FORCEPROP 2 LAST CDS_LIB dev_discrete
J 0
(-1900 2850);
PAINT MONO (-1900 2850);
DISPLAY INVISIBLE (-1900 2850);
FORCEPROP 1 LAST PATH I75
J 0
(-1850 3000);
DISPLAY 0.978723 (-1850 3000);
PAINT WHITE (-1850 3000);
DISPLAY INVISIBLE (-1850 3000);
FORCEPROP 0 LAST ROOM PVDDQ_KLM
J 0
(-1850 3050);
DISPLAY 1.021277 (-1850 3050);
PAINT ORANGE (-1850 3050);
DISPLAY INVISIBLE (-1850 3050);
FORCEADD CAP_A..1
(-2200 2850);
FORCEPROP 1 LAST VALUE 22.0UF
J 0
(-2150 2900);
DISPLAY 0.617021 (-2150 2900);
PAINT SKYBLUE (-2150 2900);
FORCEPROP 1 LAST PART_NUMBER E15431-004
J 0
(-2150 2700);
DISPLAY 0.617021 (-2150 2700);
PAINT BLUE (-2150 2700);
FORCEPROP 1 LAST TOLERANCE 20%
J 0
(-2150 2800);
DISPLAY 0.617021 (-2150 2800);
PAINT SKYBLUE (-2150 2800);
FORCEPROP 1 LAST VOLTAGE 4V
J 0
(-2150 2850);
DISPLAY 0.617021 (-2150 2850);
PAINT SKYBLUE (-2150 2850);
FORCEPROP 1 LAST MATERIAL X6S
J 0
(-2150 2750);
DISPLAY 0.617021 (-2150 2750);
PAINT SKYBLUE (-2150 2750);
FORCEPROP 1 LAST PACK_TYPE 0603V
J 0
(-2150 2650);
DISPLAY 0.617021 (-2150 2650);
PAINT SKYBLUE (-2150 2650);
FORCEPROP 1 LAST LOCATION C5G62
J 0
(-2150 2950);
DISPLAY 0.617021 (-2150 2950);
PAINT AQUA (-2150 2950);
FORCEPROP 0 LAST SIDE_SKU 1S
J 0
(-2325 2900);
DISPLAY 1.021277 (-2325 2900);
PAINT ORANGE (-2325 2900);
FORCEPROP 1 LASTPIN (-2200 2750) $PN 2
J 0
(-2190 2730);
DISPLAY 0.787234 (-2190 2730);
PAINT ORANGE (-2190 2730);
DISPLAY INVISIBLE (-2190 2730);
FORCEPROP 1 LASTPIN (-2200 2950) $PN 1
J 0
(-2190 2930);
DISPLAY 0.787234 (-2190 2930);
PAINT ORANGE (-2190 2930);
DISPLAY INVISIBLE (-2190 2930);
FORCEPROP 2 LAST CDS_LIB dev_discrete
J 0
(-2200 2850);
PAINT MONO (-2200 2850);
DISPLAY INVISIBLE (-2200 2850);
FORCEPROP 1 LAST PATH I76
J 0
(-2150 3000);
DISPLAY 0.978723 (-2150 3000);
PAINT WHITE (-2150 3000);
DISPLAY INVISIBLE (-2150 3000);
FORCEPROP 0 LAST ROOM PVDDQ_KLM
J 0
(-2150 3050);
DISPLAY 1.021277 (-2150 3050);
PAINT ORANGE (-2150 3050);
DISPLAY INVISIBLE (-2150 3050);
FORCEADD CAP_A..1
(-2550 2850);
FORCEPROP 1 LAST PACK_TYPE 0603V
J 0
(-2500 2650);
DISPLAY 0.617021 (-2500 2650);
PAINT SKYBLUE (-2500 2650);
FORCEPROP 1 LAST MATERIAL X6S
J 0
(-2500 2750);
DISPLAY 0.617021 (-2500 2750);
PAINT SKYBLUE (-2500 2750);
FORCEPROP 1 LAST VOLTAGE 4V
J 0
(-2500 2850);
DISPLAY 0.617021 (-2500 2850);
PAINT SKYBLUE (-2500 2850);
FORCEPROP 1 LAST TOLERANCE 20%
J 0
(-2500 2800);
DISPLAY 0.617021 (-2500 2800);
PAINT SKYBLUE (-2500 2800);
FORCEPROP 1 LAST PART_NUMBER E15431-004
J 0
(-2500 2700);
DISPLAY 0.617021 (-2500 2700);
PAINT BLUE (-2500 2700);
FORCEPROP 1 LAST VALUE 22.0UF
J 0
(-2500 2900);
DISPLAY 0.617021 (-2500 2900);
PAINT SKYBLUE (-2500 2900);
FORCEPROP 1 LAST LOCATION C5G61
J 0
(-2500 2950);
DISPLAY 0.617021 (-2500 2950);
PAINT AQUA (-2500 2950);
FORCEPROP 0 LAST SIDE_SKU 1S
J 0
(-2675 2900);
DISPLAY 1.021277 (-2675 2900);
PAINT ORANGE (-2675 2900);
FORCEPROP 1 LASTPIN (-2550 2750) $PN 2
J 0
(-2540 2730);
DISPLAY 0.787234 (-2540 2730);
PAINT ORANGE (-2540 2730);
DISPLAY INVISIBLE (-2540 2730);
FORCEPROP 1 LASTPIN (-2550 2950) $PN 1
J 0
(-2540 2930);
DISPLAY 0.787234 (-2540 2930);
PAINT ORANGE (-2540 2930);
DISPLAY INVISIBLE (-2540 2930);
FORCEPROP 2 LAST CDS_LIB dev_discrete
J 0
(-2550 2850);
PAINT MONO (-2550 2850);
DISPLAY INVISIBLE (-2550 2850);
FORCEPROP 1 LAST PATH I77
J 0
(-2500 3000);
DISPLAY 0.978723 (-2500 3000);
PAINT WHITE (-2500 3000);
DISPLAY INVISIBLE (-2500 3000);
FORCEPROP 0 LAST ROOM PVDDQ_KLM
J 0
(-2500 3050);
DISPLAY 1.021277 (-2500 3050);
PAINT ORANGE (-2500 3050);
DISPLAY INVISIBLE (-2500 3050);
FORCEADD CAP_A..1
(-2850 2850);
FORCEPROP 1 LAST VALUE 22.0UF
J 0
(-2800 2900);
DISPLAY 0.617021 (-2800 2900);
PAINT SKYBLUE (-2800 2900);
FORCEPROP 1 LAST MATERIAL X6S
J 0
(-2800 2750);
DISPLAY 0.617021 (-2800 2750);
PAINT SKYBLUE (-2800 2750);
FORCEPROP 1 LAST VOLTAGE 4V
J 0
(-2800 2850);
DISPLAY 0.617021 (-2800 2850);
PAINT SKYBLUE (-2800 2850);
FORCEPROP 1 LAST TOLERANCE 20%
J 0
(-2800 2800);
DISPLAY 0.617021 (-2800 2800);
PAINT SKYBLUE (-2800 2800);
FORCEPROP 1 LAST PART_NUMBER E15431-004
J 0
(-2800 2700);
DISPLAY 0.617021 (-2800 2700);
PAINT BLUE (-2800 2700);
FORCEPROP 1 LAST LOCATION C5G60
J 0
(-2800 2950);
DISPLAY 0.617021 (-2800 2950);
PAINT AQUA (-2800 2950);
FORCEPROP 1 LAST PACK_TYPE 0603V
J 0
(-2800 2650);
DISPLAY 0.617021 (-2800 2650);
PAINT SKYBLUE (-2800 2650);
FORCEPROP 0 LAST SIDE_SKU 1S
J 0
(-2975 2900);
DISPLAY 1.021277 (-2975 2900);
PAINT ORANGE (-2975 2900);
FORCEPROP 1 LASTPIN (-2850 2750) $PN 2
J 0
(-2840 2730);
DISPLAY 0.787234 (-2840 2730);
PAINT ORANGE (-2840 2730);
DISPLAY INVISIBLE (-2840 2730);
FORCEPROP 1 LASTPIN (-2850 2950) $PN 1
J 0
(-2840 2930);
DISPLAY 0.787234 (-2840 2930);
PAINT ORANGE (-2840 2930);
DISPLAY INVISIBLE (-2840 2930);
FORCEPROP 2 LAST CDS_LIB dev_discrete
J 0
(-2850 2850);
PAINT MONO (-2850 2850);
DISPLAY INVISIBLE (-2850 2850);
FORCEPROP 1 LAST PATH I78
J 0
(-2800 3000);
DISPLAY 0.978723 (-2800 3000);
PAINT WHITE (-2800 3000);
DISPLAY INVISIBLE (-2800 3000);
FORCEPROP 0 LAST ROOM PVDDQ_KLM
J 0
(-2800 3050);
DISPLAY 1.021277 (-2800 3050);
PAINT ORANGE (-2800 3050);
DISPLAY INVISIBLE (-2800 3050);
FORCEADD CAP_A..1
(-3150 2850);
FORCEPROP 1 LAST PACK_TYPE 0603V
J 0
(-3100 2650);
DISPLAY 0.617021 (-3100 2650);
PAINT SKYBLUE (-3100 2650);
FORCEPROP 1 LAST MATERIAL X6S
J 0
(-3100 2750);
DISPLAY 0.617021 (-3100 2750);
PAINT SKYBLUE (-3100 2750);
FORCEPROP 1 LAST VOLTAGE 4V
J 0
(-3100 2850);
DISPLAY 0.617021 (-3100 2850);
PAINT SKYBLUE (-3100 2850);
FORCEPROP 1 LAST TOLERANCE 20%
J 0
(-3100 2800);
DISPLAY 0.617021 (-3100 2800);
PAINT SKYBLUE (-3100 2800);
FORCEPROP 1 LAST PART_NUMBER E15431-004
J 0
(-3100 2700);
DISPLAY 0.617021 (-3100 2700);
PAINT BLUE (-3100 2700);
FORCEPROP 1 LAST VALUE 22.0UF
J 0
(-3100 2900);
DISPLAY 0.617021 (-3100 2900);
PAINT SKYBLUE (-3100 2900);
FORCEPROP 1 LAST LOCATION C5G59
J 0
(-3100 2950);
DISPLAY 0.617021 (-3100 2950);
PAINT AQUA (-3100 2950);
FORCEPROP 0 LAST SIDE_SKU 1S
J 0
(-3275 2900);
DISPLAY 1.021277 (-3275 2900);
PAINT ORANGE (-3275 2900);
FORCEPROP 1 LASTPIN (-3150 2750) $PN 2
J 0
(-3140 2730);
DISPLAY 0.787234 (-3140 2730);
PAINT ORANGE (-3140 2730);
DISPLAY INVISIBLE (-3140 2730);
FORCEPROP 1 LASTPIN (-3150 2950) $PN 1
J 0
(-3140 2930);
DISPLAY 0.787234 (-3140 2930);
PAINT ORANGE (-3140 2930);
DISPLAY INVISIBLE (-3140 2930);
FORCEPROP 2 LAST CDS_LIB dev_discrete
J 0
(-3150 2850);
PAINT MONO (-3150 2850);
DISPLAY INVISIBLE (-3150 2850);
FORCEPROP 1 LAST PATH I79
J 0
(-3100 3000);
DISPLAY 0.978723 (-3100 3000);
PAINT WHITE (-3100 3000);
DISPLAY INVISIBLE (-3100 3000);
FORCEPROP 0 LAST ROOM PVDDQ_KLM
J 0
(-3100 3050);
DISPLAY 1.021277 (-3100 3050);
PAINT ORANGE (-3100 3050);
DISPLAY INVISIBLE (-3100 3050);
FORCEADD CAP_A..1
(-700 1650);
FORCEPROP 1 LAST VALUE 22.0UF
J 0
(-650 1700);
DISPLAY 0.617021 (-650 1700);
PAINT SKYBLUE (-650 1700);
FORCEPROP 1 LAST PART_NUMBER E15431-004
J 0
(-650 1500);
DISPLAY 0.617021 (-650 1500);
PAINT BLUE (-650 1500);
FORCEPROP 1 LAST TOLERANCE 20%
J 0
(-650 1600);
DISPLAY 0.617021 (-650 1600);
PAINT SKYBLUE (-650 1600);
FORCEPROP 1 LAST VOLTAGE 4V
J 0
(-650 1650);
DISPLAY 0.617021 (-650 1650);
PAINT SKYBLUE (-650 1650);
FORCEPROP 1 LAST MATERIAL X6S
J 0
(-650 1550);
DISPLAY 0.617021 (-650 1550);
PAINT SKYBLUE (-650 1550);
FORCEPROP 1 LAST PACK_TYPE 0603V
J 0
(-650 1450);
DISPLAY 0.617021 (-650 1450);
PAINT SKYBLUE (-650 1450);
FORCEPROP 1 LAST LOCATION C5G76
J 0
(-650 1750);
DISPLAY 0.617021 (-650 1750);
PAINT AQUA (-650 1750);
FORCEPROP 0 LAST SIDE_SKU 1S
J 0
(-825 1700);
DISPLAY 1.021277 (-825 1700);
PAINT ORANGE (-825 1700);
FORCEPROP 1 LASTPIN (-700 1550) $PN 2
J 0
(-690 1530);
DISPLAY 0.787234 (-690 1530);
PAINT ORANGE (-690 1530);
DISPLAY INVISIBLE (-690 1530);
FORCEPROP 1 LASTPIN (-700 1750) $PN 1
J 0
(-690 1730);
DISPLAY 0.787234 (-690 1730);
PAINT ORANGE (-690 1730);
DISPLAY INVISIBLE (-690 1730);
FORCEPROP 0 LAST ROOM PVDDQ_KLM
J 0
(-650 1850);
DISPLAY 1.021277 (-650 1850);
PAINT ORANGE (-650 1850);
DISPLAY INVISIBLE (-650 1850);
FORCEPROP 1 LAST PATH I80
J 0
(-650 1800);
DISPLAY 0.978723 (-650 1800);
PAINT WHITE (-650 1800);
DISPLAY INVISIBLE (-650 1800);
FORCEPROP 2 LAST CDS_LIB dev_discrete
J 0
(-700 1650);
PAINT MONO (-700 1650);
DISPLAY INVISIBLE (-700 1650);
FORCEADD CAP_A..1
(-1000 1650);
FORCEPROP 1 LAST VALUE 22.0UF
J 0
(-950 1700);
DISPLAY 0.617021 (-950 1700);
PAINT SKYBLUE (-950 1700);
FORCEPROP 1 LAST PART_NUMBER E15431-004
J 0
(-950 1500);
DISPLAY 0.617021 (-950 1500);
PAINT BLUE (-950 1500);
FORCEPROP 1 LAST TOLERANCE 20%
J 0
(-950 1600);
DISPLAY 0.617021 (-950 1600);
PAINT SKYBLUE (-950 1600);
FORCEPROP 1 LAST VOLTAGE 4V
J 0
(-950 1650);
DISPLAY 0.617021 (-950 1650);
PAINT SKYBLUE (-950 1650);
FORCEPROP 1 LAST MATERIAL X6S
J 0
(-950 1550);
DISPLAY 0.617021 (-950 1550);
PAINT SKYBLUE (-950 1550);
FORCEPROP 1 LAST PACK_TYPE 0603V
J 0
(-950 1450);
DISPLAY 0.617021 (-950 1450);
PAINT SKYBLUE (-950 1450);
FORCEPROP 1 LAST LOCATION C5G75
J 0
(-950 1750);
DISPLAY 0.617021 (-950 1750);
PAINT AQUA (-950 1750);
FORCEPROP 0 LAST SIDE_SKU 1S
J 0
(-1125 1700);
DISPLAY 1.021277 (-1125 1700);
PAINT ORANGE (-1125 1700);
FORCEPROP 1 LASTPIN (-1000 1550) $PN 2
J 0
(-990 1530);
DISPLAY 0.787234 (-990 1530);
PAINT ORANGE (-990 1530);
DISPLAY INVISIBLE (-990 1530);
FORCEPROP 1 LASTPIN (-1000 1750) $PN 1
J 0
(-990 1730);
DISPLAY 0.787234 (-990 1730);
PAINT ORANGE (-990 1730);
DISPLAY INVISIBLE (-990 1730);
FORCEPROP 0 LAST ROOM PVDDQ_KLM
J 0
(-950 1850);
DISPLAY 1.021277 (-950 1850);
PAINT ORANGE (-950 1850);
DISPLAY INVISIBLE (-950 1850);
FORCEPROP 1 LAST PATH I81
J 0
(-950 1800);
DISPLAY 0.978723 (-950 1800);
PAINT WHITE (-950 1800);
DISPLAY INVISIBLE (-950 1800);
FORCEPROP 2 LAST CDS_LIB dev_discrete
J 0
(-1000 1650);
PAINT MONO (-1000 1650);
DISPLAY INVISIBLE (-1000 1650);
FORCEADD CAP_A..1
(-1300 1650);
FORCEPROP 1 LAST VALUE 22.0UF
J 0
(-1250 1700);
DISPLAY 0.617021 (-1250 1700);
PAINT SKYBLUE (-1250 1700);
FORCEPROP 1 LAST PART_NUMBER E15431-004
J 0
(-1250 1500);
DISPLAY 0.617021 (-1250 1500);
PAINT BLUE (-1250 1500);
FORCEPROP 1 LAST TOLERANCE 20%
J 0
(-1250 1600);
DISPLAY 0.617021 (-1250 1600);
PAINT SKYBLUE (-1250 1600);
FORCEPROP 1 LAST VOLTAGE 4V
J 0
(-1250 1650);
DISPLAY 0.617021 (-1250 1650);
PAINT SKYBLUE (-1250 1650);
FORCEPROP 1 LAST MATERIAL X6S
J 0
(-1250 1550);
DISPLAY 0.617021 (-1250 1550);
PAINT SKYBLUE (-1250 1550);
FORCEPROP 1 LAST PACK_TYPE 0603V
J 0
(-1250 1450);
DISPLAY 0.617021 (-1250 1450);
PAINT SKYBLUE (-1250 1450);
FORCEPROP 1 LAST LOCATION C5G74
J 0
(-1250 1750);
DISPLAY 0.617021 (-1250 1750);
PAINT AQUA (-1250 1750);
FORCEPROP 0 LAST SIDE_SKU 1S
J 0
(-1425 1700);
DISPLAY 1.021277 (-1425 1700);
PAINT ORANGE (-1425 1700);
FORCEPROP 1 LASTPIN (-1300 1550) $PN 2
J 0
(-1290 1530);
DISPLAY 0.787234 (-1290 1530);
PAINT ORANGE (-1290 1530);
DISPLAY INVISIBLE (-1290 1530);
FORCEPROP 1 LASTPIN (-1300 1750) $PN 1
J 0
(-1290 1730);
DISPLAY 0.787234 (-1290 1730);
PAINT ORANGE (-1290 1730);
DISPLAY INVISIBLE (-1290 1730);
FORCEPROP 0 LAST ROOM PVDDQ_KLM
J 0
(-1250 1850);
DISPLAY 1.021277 (-1250 1850);
PAINT ORANGE (-1250 1850);
DISPLAY INVISIBLE (-1250 1850);
FORCEPROP 1 LAST PATH I82
J 0
(-1250 1800);
DISPLAY 0.978723 (-1250 1800);
PAINT WHITE (-1250 1800);
DISPLAY INVISIBLE (-1250 1800);
FORCEPROP 2 LAST CDS_LIB dev_discrete
J 0
(-1300 1650);
PAINT MONO (-1300 1650);
DISPLAY INVISIBLE (-1300 1650);
FORCEADD CAP_A..1
(-1600 1650);
FORCEPROP 1 LAST VALUE 22.0UF
J 0
(-1550 1700);
DISPLAY 0.617021 (-1550 1700);
PAINT SKYBLUE (-1550 1700);
FORCEPROP 1 LAST PART_NUMBER E15431-004
J 0
(-1550 1500);
DISPLAY 0.617021 (-1550 1500);
PAINT BLUE (-1550 1500);
FORCEPROP 1 LAST TOLERANCE 20%
J 0
(-1550 1600);
DISPLAY 0.617021 (-1550 1600);
PAINT SKYBLUE (-1550 1600);
FORCEPROP 1 LAST VOLTAGE 4V
J 0
(-1550 1650);
DISPLAY 0.617021 (-1550 1650);
PAINT SKYBLUE (-1550 1650);
FORCEPROP 1 LAST MATERIAL X6S
J 0
(-1550 1550);
DISPLAY 0.617021 (-1550 1550);
PAINT SKYBLUE (-1550 1550);
FORCEPROP 1 LAST PACK_TYPE 0603V
J 0
(-1550 1450);
DISPLAY 0.617021 (-1550 1450);
PAINT SKYBLUE (-1550 1450);
FORCEPROP 1 LAST LOCATION C5G73
J 0
(-1550 1750);
DISPLAY 0.617021 (-1550 1750);
PAINT AQUA (-1550 1750);
FORCEPROP 0 LAST SIDE_SKU 1S
J 0
(-1725 1700);
DISPLAY 1.021277 (-1725 1700);
PAINT ORANGE (-1725 1700);
FORCEPROP 1 LASTPIN (-1600 1550) $PN 2
J 0
(-1590 1530);
DISPLAY 0.787234 (-1590 1530);
PAINT ORANGE (-1590 1530);
DISPLAY INVISIBLE (-1590 1530);
FORCEPROP 1 LASTPIN (-1600 1750) $PN 1
J 0
(-1590 1730);
DISPLAY 0.787234 (-1590 1730);
PAINT ORANGE (-1590 1730);
DISPLAY INVISIBLE (-1590 1730);
FORCEPROP 0 LAST ROOM PVDDQ_KLM
J 0
(-1550 1850);
DISPLAY 1.021277 (-1550 1850);
PAINT ORANGE (-1550 1850);
DISPLAY INVISIBLE (-1550 1850);
FORCEPROP 1 LAST PATH I83
J 0
(-1550 1800);
DISPLAY 0.978723 (-1550 1800);
PAINT WHITE (-1550 1800);
DISPLAY INVISIBLE (-1550 1800);
FORCEPROP 2 LAST CDS_LIB dev_discrete
J 0
(-1600 1650);
PAINT MONO (-1600 1650);
DISPLAY INVISIBLE (-1600 1650);
FORCEADD CAP_A..1
(-1900 1650);
FORCEPROP 1 LAST VALUE 22.0UF
J 0
(-1850 1700);
DISPLAY 0.617021 (-1850 1700);
PAINT SKYBLUE (-1850 1700);
FORCEPROP 1 LAST PART_NUMBER E15431-004
J 0
(-1850 1500);
DISPLAY 0.617021 (-1850 1500);
PAINT BLUE (-1850 1500);
FORCEPROP 1 LAST TOLERANCE 20%
J 0
(-1850 1600);
DISPLAY 0.617021 (-1850 1600);
PAINT SKYBLUE (-1850 1600);
FORCEPROP 1 LAST VOLTAGE 4V
J 0
(-1850 1650);
DISPLAY 0.617021 (-1850 1650);
PAINT SKYBLUE (-1850 1650);
FORCEPROP 1 LAST MATERIAL X6S
J 0
(-1850 1550);
DISPLAY 0.617021 (-1850 1550);
PAINT SKYBLUE (-1850 1550);
FORCEPROP 1 LAST PACK_TYPE 0603V
J 0
(-1850 1450);
DISPLAY 0.617021 (-1850 1450);
PAINT SKYBLUE (-1850 1450);
FORCEPROP 1 LAST LOCATION C5G72
J 0
(-1850 1750);
DISPLAY 0.617021 (-1850 1750);
PAINT AQUA (-1850 1750);
FORCEPROP 0 LAST SIDE_SKU 1S
J 0
(-2025 1700);
DISPLAY 1.021277 (-2025 1700);
PAINT ORANGE (-2025 1700);
FORCEPROP 1 LASTPIN (-1900 1550) $PN 2
J 0
(-1890 1530);
DISPLAY 0.787234 (-1890 1530);
PAINT ORANGE (-1890 1530);
DISPLAY INVISIBLE (-1890 1530);
FORCEPROP 1 LASTPIN (-1900 1750) $PN 1
J 0
(-1890 1730);
DISPLAY 0.787234 (-1890 1730);
PAINT ORANGE (-1890 1730);
DISPLAY INVISIBLE (-1890 1730);
FORCEPROP 0 LAST ROOM PVDDQ_KLM
J 0
(-1850 1850);
DISPLAY 1.021277 (-1850 1850);
PAINT ORANGE (-1850 1850);
DISPLAY INVISIBLE (-1850 1850);
FORCEPROP 1 LAST PATH I84
J 0
(-1850 1800);
DISPLAY 0.978723 (-1850 1800);
PAINT WHITE (-1850 1800);
DISPLAY INVISIBLE (-1850 1800);
FORCEPROP 2 LAST CDS_LIB dev_discrete
J 0
(-1900 1650);
PAINT MONO (-1900 1650);
DISPLAY INVISIBLE (-1900 1650);
FORCEADD CAP_A..1
(-2200 1650);
FORCEPROP 1 LAST PACK_TYPE 0603V
J 0
(-2150 1450);
DISPLAY 0.617021 (-2150 1450);
PAINT SKYBLUE (-2150 1450);
FORCEPROP 1 LAST MATERIAL X6S
J 0
(-2150 1550);
DISPLAY 0.617021 (-2150 1550);
PAINT SKYBLUE (-2150 1550);
FORCEPROP 1 LAST VOLTAGE 4V
J 0
(-2150 1650);
DISPLAY 0.617021 (-2150 1650);
PAINT SKYBLUE (-2150 1650);
FORCEPROP 1 LAST TOLERANCE 20%
J 0
(-2150 1600);
DISPLAY 0.617021 (-2150 1600);
PAINT SKYBLUE (-2150 1600);
FORCEPROP 1 LAST PART_NUMBER E15431-004
J 0
(-2150 1500);
DISPLAY 0.617021 (-2150 1500);
PAINT BLUE (-2150 1500);
FORCEPROP 1 LAST VALUE 22.0UF
J 0
(-2150 1700);
DISPLAY 0.617021 (-2150 1700);
PAINT SKYBLUE (-2150 1700);
FORCEPROP 1 LAST LOCATION C5G71
J 0
(-2150 1750);
DISPLAY 0.617021 (-2150 1750);
PAINT AQUA (-2150 1750);
FORCEPROP 0 LAST SIDE_SKU 1S
J 0
(-2325 1700);
DISPLAY 1.021277 (-2325 1700);
PAINT ORANGE (-2325 1700);
FORCEPROP 1 LASTPIN (-2200 1550) $PN 2
J 0
(-2190 1530);
DISPLAY 0.787234 (-2190 1530);
PAINT ORANGE (-2190 1530);
DISPLAY INVISIBLE (-2190 1530);
FORCEPROP 1 LASTPIN (-2200 1750) $PN 1
J 0
(-2190 1730);
DISPLAY 0.787234 (-2190 1730);
PAINT ORANGE (-2190 1730);
DISPLAY INVISIBLE (-2190 1730);
FORCEPROP 0 LAST ROOM PVDDQ_KLM
J 0
(-2150 1850);
DISPLAY 1.021277 (-2150 1850);
PAINT ORANGE (-2150 1850);
DISPLAY INVISIBLE (-2150 1850);
FORCEPROP 1 LAST PATH I85
J 0
(-2150 1800);
DISPLAY 0.978723 (-2150 1800);
PAINT WHITE (-2150 1800);
DISPLAY INVISIBLE (-2150 1800);
FORCEPROP 2 LAST CDS_LIB dev_discrete
J 0
(-2200 1650);
PAINT MONO (-2200 1650);
DISPLAY INVISIBLE (-2200 1650);
FORCEADD CAP_A..1
(-2550 1650);
FORCEPROP 1 LAST VALUE 22.0UF
J 0
(-2500 1700);
DISPLAY 0.617021 (-2500 1700);
PAINT SKYBLUE (-2500 1700);
FORCEPROP 1 LAST PART_NUMBER E15431-004
J 0
(-2500 1500);
DISPLAY 0.617021 (-2500 1500);
PAINT BLUE (-2500 1500);
FORCEPROP 1 LAST MATERIAL X6S
J 0
(-2500 1550);
DISPLAY 0.617021 (-2500 1550);
PAINT SKYBLUE (-2500 1550);
FORCEPROP 1 LAST PACK_TYPE 0603V
J 0
(-2500 1450);
DISPLAY 0.617021 (-2500 1450);
PAINT SKYBLUE (-2500 1450);
FORCEPROP 1 LAST VOLTAGE 4V
J 0
(-2500 1650);
DISPLAY 0.617021 (-2500 1650);
PAINT SKYBLUE (-2500 1650);
FORCEPROP 1 LAST TOLERANCE 20%
J 0
(-2500 1600);
DISPLAY 0.617021 (-2500 1600);
PAINT SKYBLUE (-2500 1600);
FORCEPROP 1 LAST LOCATION C5G70
J 0
(-2500 1750);
DISPLAY 0.617021 (-2500 1750);
PAINT AQUA (-2500 1750);
FORCEPROP 0 LAST SIDE_SKU 1S
J 0
(-2675 1700);
DISPLAY 1.021277 (-2675 1700);
PAINT ORANGE (-2675 1700);
FORCEPROP 1 LASTPIN (-2550 1550) $PN 2
J 0
(-2540 1530);
DISPLAY 0.787234 (-2540 1530);
PAINT ORANGE (-2540 1530);
DISPLAY INVISIBLE (-2540 1530);
FORCEPROP 1 LASTPIN (-2550 1750) $PN 1
J 0
(-2540 1730);
DISPLAY 0.787234 (-2540 1730);
PAINT ORANGE (-2540 1730);
DISPLAY INVISIBLE (-2540 1730);
FORCEPROP 0 LAST ROOM PVDDQ_KLM
J 0
(-2500 1850);
DISPLAY 1.021277 (-2500 1850);
PAINT ORANGE (-2500 1850);
DISPLAY INVISIBLE (-2500 1850);
FORCEPROP 1 LAST PATH I86
J 0
(-2500 1800);
DISPLAY 0.978723 (-2500 1800);
PAINT WHITE (-2500 1800);
DISPLAY INVISIBLE (-2500 1800);
FORCEPROP 2 LAST CDS_LIB dev_discrete
J 0
(-2550 1650);
PAINT MONO (-2550 1650);
DISPLAY INVISIBLE (-2550 1650);
FORCEADD CAP_A..1
(-2850 1650);
FORCEPROP 1 LAST VALUE 22.0UF
J 0
(-2800 1700);
DISPLAY 0.617021 (-2800 1700);
PAINT SKYBLUE (-2800 1700);
FORCEPROP 1 LAST TOLERANCE 20%
J 0
(-2800 1600);
DISPLAY 0.617021 (-2800 1600);
PAINT SKYBLUE (-2800 1600);
FORCEPROP 1 LAST VOLTAGE 4V
J 0
(-2800 1650);
DISPLAY 0.617021 (-2800 1650);
PAINT SKYBLUE (-2800 1650);
FORCEPROP 1 LAST MATERIAL X6S
J 0
(-2800 1550);
DISPLAY 0.617021 (-2800 1550);
PAINT SKYBLUE (-2800 1550);
FORCEPROP 1 LAST PART_NUMBER E15431-004
J 0
(-2800 1500);
DISPLAY 0.617021 (-2800 1500);
PAINT BLUE (-2800 1500);
FORCEPROP 1 LAST PACK_TYPE 0603V
J 0
(-2800 1450);
DISPLAY 0.617021 (-2800 1450);
PAINT SKYBLUE (-2800 1450);
FORCEPROP 1 LAST LOCATION C5G69
J 0
(-2800 1750);
DISPLAY 0.617021 (-2800 1750);
PAINT AQUA (-2800 1750);
FORCEPROP 0 LAST SIDE_SKU 1S
J 0
(-2975 1700);
DISPLAY 1.021277 (-2975 1700);
PAINT ORANGE (-2975 1700);
FORCEPROP 1 LASTPIN (-2850 1550) $PN 2
J 0
(-2840 1530);
DISPLAY 0.787234 (-2840 1530);
PAINT ORANGE (-2840 1530);
DISPLAY INVISIBLE (-2840 1530);
FORCEPROP 1 LASTPIN (-2850 1750) $PN 1
J 0
(-2840 1730);
DISPLAY 0.787234 (-2840 1730);
PAINT ORANGE (-2840 1730);
DISPLAY INVISIBLE (-2840 1730);
FORCEPROP 0 LAST ROOM PVDDQ_KLM
J 0
(-2800 1850);
DISPLAY 1.021277 (-2800 1850);
PAINT ORANGE (-2800 1850);
DISPLAY INVISIBLE (-2800 1850);
FORCEPROP 1 LAST PATH I87
J 0
(-2800 1800);
DISPLAY 0.978723 (-2800 1800);
PAINT WHITE (-2800 1800);
DISPLAY INVISIBLE (-2800 1800);
FORCEPROP 2 LAST CDS_LIB dev_discrete
J 0
(-2850 1650);
PAINT MONO (-2850 1650);
DISPLAY INVISIBLE (-2850 1650);
FORCEADD CAP_A..1
(-3150 1650);
FORCEPROP 1 LAST VALUE 22.0UF
J 0
(-3100 1700);
DISPLAY 0.617021 (-3100 1700);
PAINT SKYBLUE (-3100 1700);
FORCEPROP 1 LAST PART_NUMBER E15431-004
J 0
(-3100 1500);
DISPLAY 0.617021 (-3100 1500);
PAINT BLUE (-3100 1500);
FORCEPROP 1 LAST PACK_TYPE 0603V
J 0
(-3100 1450);
DISPLAY 0.617021 (-3100 1450);
PAINT SKYBLUE (-3100 1450);
FORCEPROP 1 LAST MATERIAL X6S
J 0
(-3100 1550);
DISPLAY 0.617021 (-3100 1550);
PAINT SKYBLUE (-3100 1550);
FORCEPROP 1 LAST TOLERANCE 20%
J 0
(-3100 1600);
DISPLAY 0.617021 (-3100 1600);
PAINT SKYBLUE (-3100 1600);
FORCEPROP 1 LAST VOLTAGE 4V
J 0
(-3100 1650);
DISPLAY 0.617021 (-3100 1650);
PAINT SKYBLUE (-3100 1650);
FORCEPROP 1 LAST LOCATION C5G68
J 0
(-3100 1750);
DISPLAY 0.617021 (-3100 1750);
PAINT AQUA (-3100 1750);
FORCEPROP 0 LAST SIDE_SKU 1S
J 0
(-3275 1700);
DISPLAY 1.021277 (-3275 1700);
PAINT ORANGE (-3275 1700);
FORCEPROP 1 LASTPIN (-3150 1550) $PN 2
J 0
(-3140 1530);
DISPLAY 0.787234 (-3140 1530);
PAINT ORANGE (-3140 1530);
DISPLAY INVISIBLE (-3140 1530);
FORCEPROP 1 LASTPIN (-3150 1750) $PN 1
J 0
(-3140 1730);
DISPLAY 0.787234 (-3140 1730);
PAINT ORANGE (-3140 1730);
DISPLAY INVISIBLE (-3140 1730);
FORCEPROP 0 LAST ROOM PVDDQ_KLM
J 0
(-3100 1850);
DISPLAY 1.021277 (-3100 1850);
PAINT ORANGE (-3100 1850);
DISPLAY INVISIBLE (-3100 1850);
FORCEPROP 1 LAST PATH I88
J 0
(-3100 1800);
DISPLAY 0.978723 (-3100 1800);
PAINT WHITE (-3100 1800);
DISPLAY INVISIBLE (-3100 1800);
FORCEPROP 2 LAST CDS_LIB dev_discrete
J 0
(-3150 1650);
PAINT MONO (-3150 1650);
DISPLAY INVISIBLE (-3150 1650);
FORCEADD PVDDQ_ABC..1
(-7400 3100);
FORCEPROP 3 LASTPIN (-7400 3050) SIG_NAME PVDDQ_ABC\g
J 0
(-7390 3060);
DISPLAY 0.659574 (-7390 3060);
PAINT MONO (-7390 3060);
DISPLAY INVISIBLE (-7390 3060);
FORCEPROP 1 LAST HDL_POWER PVDDQ_ABC
J 1
(-7400 3150);
DISPLAY 0.872340 (-7400 3150);
PAINT GREEN (-7400 3150);
DISPLAY INVISIBLE (-7400 3150);
FORCEPROP 1 LAST BODY_TYPE PLUMBING
J 0
(-7445 3057);
DISPLAY 0.340426 (-7445 3057);
PAINT GREEN (-7445 3057);
DISPLAY INVISIBLE (-7445 3057);
FORCEPROP 1 LAST PATH I9
J 0
(-7350 3125);
DISPLAY 0.872340 (-7350 3125);
PAINT AQUA (-7350 3125);
DISPLAY INVISIBLE (-7350 3125);
FORCEPROP 2 LAST CDS_LIB mstr_symbols
J 0
(-7400 3100);
PAINT MONO (-7400 3100);
DISPLAY INVISIBLE (-7400 3100);
FORCEPROP 2 LAST ROOM VDDQ_ABC_PWR_VR
J 0
(-7400 3200);
DISPLAY 1.936170 (-7400 3200);
PAINT ORANGE (-7400 3200);
DISPLAY INVISIBLE (-7400 3200);
FORCEPROP 2 LAST BOM_COST PROC_SOCKET 
J 0
(-7400 3200);
DISPLAY 1.446809 (-7400 3200);
PAINT MONO (-7400 3200);
DISPLAY INVISIBLE (-7400 3200);
FORCEPROP 1 LAST VOLTAGE 1.2V
J 0
(-7445 3057);
DISPLAY 0.340426 (-7445 3057);
PAINT GREEN (-7445 3057);
DISPLAY INVISIBLE (-7445 3057);
FORCEADD INTEL_CORP_BPAGE..1
(0 0);
FORCEPROP 1 LAST CDS_CON_LAST_MODIFIED Tue Dec 01 11:52:32 2015
J 0
(-1425 325);
PAINT ORANGE (-1425 325);
DISPLAY INVISIBLE (-1425 325);
FORCEPROP 1 LAST CUSTOM_TXT_CDS <CURRENT_DESIGN_SHEET> OF <TOTAL_DESIGN_SHEETS>
J 0
(-500 25);
PAINT GREEN (-500 25);
FORCEPROP 1 LAST CUSTOM_TXT_CDS <CON_LAST_MODIFIED>
J 0
(-1925 350);
PAINT GREEN (-1925 350);
FORCEPROP 2 LAST CUSTOM_TXT_CDS <XR_PAGE_TITLE>
J 0
(-7890 5250);
DISPLAY 0.638298 (-7890 5250);
PAINT PINK (-7890 5250);
DISPLAY INVISIBLE (-7890 5250);
FORCEPROP 1 LAST SCH_ADDRESS1 2200 Mission College Blvd.
J 0
(-3975 125);
DISPLAY 0.872340 (-3975 125);
PAINT GREEN (-3975 125);
FORCEPROP 1 LAST SCH_ADDRESS2 P.O. BOX 58119
J 0
(-3975 75);
DISPLAY 0.872340 (-3975 75);
PAINT GREEN (-3975 75);
FORCEPROP 1 LAST SCH_ADDRESS3 Santa Clara, CA 95052-8119
J 0
(-3975 25);
DISPLAY 0.872340 (-3975 25);
PAINT GREEN (-3975 25);
FORCEPROP 1 LAST SCH_DEPT UNKNOWN
J 1
(-4450 100);
DISPLAY 1.255319 (-4450 100);
PAINT ORANGE (-4450 100);
FORCEPROP 1 LAST SCH_REV 0.1
J 0
(-250 150);
DISPLAY 1.170213 (-250 150);
PAINT GREEN (-250 150);
FORCEPROP 1 LAST SCH_NUMBER 000000-000
J 0
(-1300 150);
DISPLAY 1.702128 (-1300 150);
PAINT GREEN (-1300 150);
FORCEPROP 1 LAST SCH_TITLE ADD DIMM CAP (1/2)
J 0
(-7950 50);
DISPLAY 2.468085 (-7950 50);
PAINT ORANGE (-7950 50);
FORCEPROP 1 LAST COMMENT_BODY TRUE
J 0
(12 12);
DISPLAY 0.468085 (12 12);
PAINT GREEN (12 12);
DISPLAY INVISIBLE (12 12);
FORCEPROP 2 LAST CDS_LIB mstr_symbols
J 0
(0 0);
PAINT MONO (0 0);
DISPLAY INVISIBLE (0 0);
FORCEPROP 2 LAST PAGE_BORDER TRUE
J 0
(-7890 5250);
DISPLAY 0.638298 (-7890 5250);
PAINT PINK (-7890 5250);
DISPLAY INVISIBLE (-7890 5250);
FORCEPROP 2 LAST CDS_XR_PAGE_TITLE CR-242 : @BASEBOARD_FAB2_LIB.BASEBOARD_FAB2(SCH_1):PAGE242
J 0
(-7890 5250);
DISPLAY 0.638298 (-7890 5250);
PAINT PINK (-7890 5250);
DISPLAY INVISIBLE (-7890 5250);
WIRE 16 -1 (-4950 1500)(-4950 1300);
WIRE 16 -1 (-4950 1300)(-5250 1300);
WIRE 16 -1 (-5250 1500)(-5250 1300);
WIRE 16 -1 (-5250 1300)(-5550 1300);
WIRE 16 -1 (-5550 1500)(-5550 1300);
WIRE 16 -1 (-5550 1300)(-5850 1300);
WIRE 16 -1 (-5850 1500)(-5850 1300);
WIRE 16 -1 (-5850 1300)(-6150 1300);
WIRE 16 -1 (-6150 1500)(-6150 1300);
WIRE 16 -1 (-6150 1300)(-6450 1300);
WIRE 16 -1 (-6450 1500)(-6450 1300);
WIRE 16 -1 (-6450 1300)(-6800 1300);
WIRE 16 -1 (-6800 1500)(-6800 1300);
WIRE 16 -1 (-6800 1300)(-7100 1300);
WIRE 16 -1 (-7100 1500)(-7100 1300);
WIRE 16 -1 (-7100 1300)(-7400 1300);
WIRE 16 -1 (-7400 1500)(-7400 1300);
WIRE 16 -1 (-7400 1300)(-7400 1150);
WIRE 16 -1 (-7000 3575)(-7000 3800);
WIRE 16 -1 (-7400 3575)(-7000 3575);
WIRE 16 -1 (-7400 3800)(-7400 3575);
WIRE 16 -1 (-7400 3425)(-7400 3575);
WIRE 16 -1 (-7000 4000)(-7000 4175);
WIRE 16 -1 (-7000 4175)(-7400 4175);
WIRE 16 -1 (-7400 4175)(-7400 4275);
WIRE 16 -1 (-7400 4175)(-7400 4000);
WIRE 16 -1 (-700 1550)(-700 1350);
WIRE 16 -1 (-700 1350)(-1000 1350);
WIRE 16 -1 (-1000 1550)(-1000 1350);
WIRE 16 -1 (-1000 1350)(-1300 1350);
WIRE 16 -1 (-1300 1550)(-1300 1350);
WIRE 16 -1 (-1300 1350)(-1600 1350);
WIRE 16 -1 (-1600 1550)(-1600 1350);
WIRE 16 -1 (-1600 1350)(-1900 1350);
WIRE 16 -1 (-1900 1550)(-1900 1350);
WIRE 16 -1 (-1900 1350)(-2200 1350);
WIRE 16 -1 (-2200 1550)(-2200 1350);
WIRE 16 -1 (-2200 1350)(-2550 1350);
WIRE 16 -1 (-2550 1550)(-2550 1350);
WIRE 16 -1 (-2550 1350)(-2850 1350);
WIRE 16 -1 (-2850 1550)(-2850 1350);
WIRE 16 -1 (-2850 1350)(-3150 1350);
WIRE 16 -1 (-3150 1550)(-3150 1350);
WIRE 16 -1 (-3150 1350)(-3150 1200);
WIRE 16 -1 (-700 1750)(-700 1850);
WIRE 16 -1 (-1000 1850)(-700 1850);
WIRE 16 -1 (-1000 1750)(-1000 1850);
WIRE 16 -1 (-1000 1850)(-1300 1850);
WIRE 16 -1 (-1300 1750)(-1300 1850);
WIRE 16 -1 (-1300 1850)(-1600 1850);
WIRE 16 -1 (-1600 1750)(-1600 1850);
WIRE 16 -1 (-1900 1850)(-1600 1850);
WIRE 16 -1 (-1900 1750)(-1900 1850);
WIRE 16 -1 (-2200 1850)(-1900 1850);
WIRE 16 -1 (-2200 1750)(-2200 1850);
WIRE 16 -1 (-2550 1850)(-2200 1850);
WIRE 16 -1 (-2550 1750)(-2550 1850);
WIRE 16 -1 (-2850 1850)(-2550 1850);
WIRE 16 -1 (-2850 1750)(-2850 1850);
WIRE 16 -1 (-3150 1850)(-2850 1850);
WIRE 16 -1 (-3150 1750)(-3150 1850);
WIRE 16 -1 (-3150 1850)(-3150 1925);
WIRE 16 -1 (-4950 1700)(-4950 1800);
WIRE 16 -1 (-5250 1800)(-4950 1800);
WIRE 16 -1 (-5250 1700)(-5250 1800);
WIRE 16 -1 (-5250 1800)(-5550 1800);
WIRE 16 -1 (-5550 1700)(-5550 1800);
WIRE 16 -1 (-5550 1800)(-5850 1800);
WIRE 16 -1 (-5850 1700)(-5850 1800);
WIRE 16 -1 (-6150 1800)(-5850 1800);
WIRE 16 -1 (-6150 1700)(-6150 1800);
WIRE 16 -1 (-6450 1800)(-6150 1800);
WIRE 16 -1 (-6450 1700)(-6450 1800);
WIRE 16 -1 (-6800 1800)(-6450 1800);
WIRE 16 -1 (-6800 1700)(-6800 1800);
WIRE 16 -1 (-7100 1800)(-6800 1800);
WIRE 16 -1 (-7100 1700)(-7100 1800);
WIRE 16 -1 (-7400 1800)(-7100 1800);
WIRE 16 -1 (-7400 1700)(-7400 1800);
WIRE 16 -1 (-7400 1800)(-7400 1875);
WIRE 16 -1 (-700 2750)(-700 2550);
WIRE 16 -1 (-700 2550)(-1000 2550);
WIRE 16 -1 (-1000 2750)(-1000 2550);
WIRE 16 -1 (-1000 2550)(-1300 2550);
WIRE 16 -1 (-1300 2750)(-1300 2550);
WIRE 16 -1 (-1300 2550)(-1600 2550);
WIRE 16 -1 (-1600 2750)(-1600 2550);
WIRE 16 -1 (-1600 2550)(-1900 2550);
WIRE 16 -1 (-1900 2750)(-1900 2550);
WIRE 16 -1 (-1900 2550)(-2200 2550);
WIRE 16 -1 (-2200 2750)(-2200 2550);
WIRE 16 -1 (-2200 2550)(-2550 2550);
WIRE 16 -1 (-2550 2750)(-2550 2550);
WIRE 16 -1 (-2550 2550)(-2850 2550);
WIRE 16 -1 (-2850 2750)(-2850 2550);
WIRE 16 -1 (-2850 2550)(-3150 2550);
WIRE 16 -1 (-3150 2750)(-3150 2550);
WIRE 16 -1 (-3150 2550)(-3150 2400);
WIRE 16 -1 (-700 2950)(-700 3050);
WIRE 16 -1 (-1000 3050)(-700 3050);
WIRE 16 -1 (-1000 2950)(-1000 3050);
WIRE 16 -1 (-1000 3050)(-1300 3050);
WIRE 16 -1 (-1300 2950)(-1300 3050);
WIRE 16 -1 (-1300 3050)(-1600 3050);
WIRE 16 -1 (-1600 2950)(-1600 3050);
WIRE 16 -1 (-1900 3050)(-1600 3050);
WIRE 16 -1 (-1900 2950)(-1900 3050);
WIRE 16 -1 (-2200 3050)(-1900 3050);
WIRE 16 -1 (-2200 2950)(-2200 3050);
WIRE 16 -1 (-2550 3050)(-2200 3050);
WIRE 16 -1 (-2550 2950)(-2550 3050);
WIRE 16 -1 (-2850 3050)(-2550 3050);
WIRE 16 -1 (-2850 2950)(-2850 3050);
WIRE 16 -1 (-3150 3050)(-2850 3050);
WIRE 16 -1 (-3150 2950)(-3150 3050);
WIRE 16 -1 (-3150 3050)(-3150 3125);
WIRE 16 -1 (-2750 3600)(-2750 3825);
WIRE 16 -1 (-3150 3600)(-2750 3600);
WIRE 16 -1 (-3150 3825)(-3150 3600);
WIRE 16 -1 (-3150 3450)(-3150 3600);
WIRE 16 -1 (-2750 4025)(-2750 4200);
WIRE 16 -1 (-2750 4200)(-3150 4200);
WIRE 16 -1 (-3150 4200)(-3150 4300);
WIRE 16 -1 (-3150 4200)(-3150 4025);
WIRE 16 -1 (-4950 2675)(-4950 2475);
WIRE 16 -1 (-4950 2475)(-5250 2475);
WIRE 16 -1 (-5250 2675)(-5250 2475);
WIRE 16 -1 (-5250 2475)(-5550 2475);
WIRE 16 -1 (-5550 2675)(-5550 2475);
WIRE 16 -1 (-5550 2475)(-5850 2475);
WIRE 16 -1 (-5850 2675)(-5850 2475);
WIRE 16 -1 (-5850 2475)(-6150 2475);
WIRE 16 -1 (-6150 2675)(-6150 2475);
WIRE 16 -1 (-6150 2475)(-6450 2475);
WIRE 16 -1 (-6450 2675)(-6450 2475);
WIRE 16 -1 (-6450 2475)(-6800 2475);
WIRE 16 -1 (-6800 2675)(-6800 2475);
WIRE 16 -1 (-6800 2475)(-7100 2475);
WIRE 16 -1 (-7100 2675)(-7100 2475);
WIRE 16 -1 (-7100 2475)(-7400 2475);
WIRE 16 -1 (-7400 2675)(-7400 2475);
WIRE 16 -1 (-7400 2475)(-7400 2325);
WIRE 16 -1 (-4950 2875)(-4950 2975);
WIRE 16 -1 (-5250 2975)(-4950 2975);
WIRE 16 -1 (-5250 2875)(-5250 2975);
WIRE 16 -1 (-5250 2975)(-5550 2975);
WIRE 16 -1 (-5550 2875)(-5550 2975);
WIRE 16 -1 (-5550 2975)(-5850 2975);
WIRE 16 -1 (-5850 2875)(-5850 2975);
WIRE 16 -1 (-6150 2975)(-5850 2975);
WIRE 16 -1 (-6150 2875)(-6150 2975);
WIRE 16 -1 (-6450 2975)(-6150 2975);
WIRE 16 -1 (-6450 2875)(-6450 2975);
WIRE 16 -1 (-6800 2975)(-6450 2975);
WIRE 16 -1 (-6800 2875)(-6800 2975);
WIRE 16 -1 (-7100 2975)(-6800 2975);
WIRE 16 -1 (-7100 2875)(-7100 2975);
WIRE 16 -1 (-7400 2975)(-7100 2975);
WIRE 16 -1 (-7400 2875)(-7400 2975);
WIRE 16 -1 (-7400 2975)(-7400 3050);
DOT 1 (-7400 4175);
DOT 1 (-7400 3575);
DOT 1 (-6800 1300);
DOT 1 (-6450 1300);
DOT 1 (-7400 1300);
DOT 1 (-7400 1800);
DOT 1 (-7100 1800);
DOT 1 (-7400 2975);
DOT 1 (-6800 2475);
DOT 1 (-7100 2975);
DOT 1 (-6800 2975);
DOT 1 (-6450 2475);
DOT 1 (-6450 2975);
DOT 1 (-6150 1300);
DOT 1 (-5850 1300);
DOT 1 (-5550 1300);
DOT 1 (-5250 1300);
DOT 1 (-5550 1800);
DOT 1 (-5250 1800);
DOT 1 (-5850 2475);
DOT 1 (-6150 2475);
DOT 1 (-6150 2975);
DOT 1 (-5850 2975);
DOT 1 (-5250 2475);
DOT 1 (-5550 2475);
DOT 1 (-5550 2975);
DOT 1 (-5250 2975);
DOT 1 (-3150 1350);
DOT 1 (-3150 1850);
DOT 1 (-2850 1850);
DOT 1 (-2550 1350);
DOT 1 (-2200 1350);
DOT 1 (-2550 1850);
DOT 1 (-2200 1850);
DOT 1 (-3150 2550);
DOT 1 (-3150 3600);
DOT 1 (-2850 2550);
DOT 1 (-2850 3050);
DOT 1 (-2550 2550);
DOT 1 (-2550 3050);
DOT 1 (-2200 3050);
DOT 1 (-1900 1350);
DOT 1 (-1600 1350);
DOT 1 (-1900 1850);
DOT 1 (-1600 1850);
DOT 1 (-1300 1350);
DOT 1 (-1300 1850);
DOT 1 (-1000 1350);
DOT 1 (-1000 1850);
DOT 1 (-1900 2550);
DOT 1 (-1900 3050);
DOT 1 (-1600 3050);
DOT 1 (-1300 2550);
DOT 1 (-1300 3050);
DOT 1 (-1000 2550);
DOT 1 (-1000 3050);
DOT 1 (-3150 4200);
DOT 1 (-6800 1800);
DOT 1 (-7400 2475);
DOT 1 (-7100 2475);
DOT 1 (-5850 1800);
DOT 1 (-7100 1300);
DOT 1 (-6150 1800);
DOT 1 (-6450 1800);
DOT 1 (-2200 2550);
DOT 1 (-3150 3050);
DOT 1 (-1600 2550);
DOT 1 (-2850 1350);
FORCENOTE
TP FAB1 ADD CAP ON DIMM BOTTOM SIDE 1116
(-4955 622) 0;
DISPLAY LEFT (-4955 622);
DISPLAY 1.021277 (-4955 622);
PAINT RED (-4955 622);
QUIT
